(kicad_sch (version 20230121) (generator eeschema)

  (paper "A3")

  (title_block
    (title "Data Center RDIMM DDR4 Tester")
    (date "2024-09-30")
    (rev "1.2.4")
    (company "Antmicro Ltd.")
    (comment 1 "www.antmicro.com")
    (comment 2 "Antmicro Ltd")
  )

  (junction (at 340.995 135.89) (diameter 0) (color 0 0 0 0)
  )
  (junction (at 353.695 97.79) (diameter 0) (color 0 0 0 0)
  )
  (junction (at 353.695 116.84) (diameter 0) (color 0 0 0 0)
  )
  (junction (at 346.71 77.47) (diameter 0) (color 0 0 0 0)
  )
  (junction (at 334.645 155.575) (diameter 0) (color 0 0 0 0)
  )
  (junction (at 340.36 57.15) (diameter 0) (color 0 0 0 0)
  )
  (junction (at 347.345 116.84) (diameter 0) (color 0 0 0 0)
  )
  (junction (at 334.645 97.79) (diameter 0) (color 0 0 0 0)
  )
  (junction (at 359.41 57.15) (diameter 0) (color 0 0 0 0)
  )
  (junction (at 347.345 97.79) (diameter 0) (color 0 0 0 0)
  )
  (junction (at 340.36 77.47) (diameter 0) (color 0 0 0 0)
  )
  (junction (at 353.695 135.89) (diameter 0) (color 0 0 0 0)
  )
  (junction (at 334.645 116.84) (diameter 0) (color 0 0 0 0)
  )
  (junction (at 334.01 77.47) (diameter 0) (color 0 0 0 0)
  )
  (junction (at 360.045 97.79) (diameter 0) (color 0 0 0 0)
  )
  (junction (at 353.06 57.15) (diameter 0) (color 0 0 0 0)
  )
  (junction (at 334.645 135.89) (diameter 0) (color 0 0 0 0)
  )
  (junction (at 353.06 77.47) (diameter 0) (color 0 0 0 0)
  )
  (junction (at 365.76 57.15) (diameter 0) (color 0 0 0 0)
  )
  (junction (at 50.8 48.895) (diameter 0) (color 0 0 0 0)
  )
  (junction (at 208.28 123.825) (diameter 0) (color 0 0 0 0)
  )
  (junction (at 360.045 116.84) (diameter 0) (color 0 0 0 0)
  )
  (junction (at 340.995 97.79) (diameter 0) (color 0 0 0 0)
  )
  (junction (at 334.01 57.15) (diameter 0) (color 0 0 0 0)
  )
  (junction (at 340.995 116.84) (diameter 0) (color 0 0 0 0)
  )
  (junction (at 210.82 123.825) (diameter 0) (color 0 0 0 0)
  )
  (junction (at 359.41 77.47) (diameter 0) (color 0 0 0 0)
  )
  (junction (at 365.76 77.47) (diameter 0) (color 0 0 0 0)
  )
  (junction (at 347.345 135.89) (diameter 0) (color 0 0 0 0)
  )
  (junction (at 346.71 57.15) (diameter 0) (color 0 0 0 0)
  )

  (no_connect (at 254.635 133.35))
  (no_connect (at 254.635 128.27))
  (no_connect (at 254.635 130.81))

  (wire (pts (xy 105.41 90.805) (xy 86.995 90.805))
    (stroke (width 0) (type default))
  )
  (wire (pts (xy 224.155 114.3) (xy 219.075 114.3))
    (stroke (width 0) (type default))
  )
  (wire (pts (xy 105.41 106.045) (xy 86.995 106.045))
    (stroke (width 0) (type default))
  )
  (wire (pts (xy 372.11 57.15) (xy 372.11 59.69))
    (stroke (width 0) (type default))
  )
  (wire (pts (xy 105.41 172.085) (xy 86.995 172.085))
    (stroke (width 0) (type default))
  )
  (wire (pts (xy 360.045 116.84) (xy 360.045 119.38))
    (stroke (width 0) (type default))
  )
  (wire (pts (xy 346.71 77.47) (xy 353.06 77.47))
    (stroke (width 0) (type default))
  )
  (wire (pts (xy 135.89 120.015) (xy 154.305 120.015))
    (stroke (width 0) (type default))
  )
  (polyline (pts (xy 379.095 48.895) (xy 379.095 173.355))
    (stroke (width 0) (type default))
  )

  (wire (pts (xy 105.41 80.645) (xy 86.995 80.645))
    (stroke (width 0) (type default))
  )
  (wire (pts (xy 135.89 117.475) (xy 154.305 117.475))
    (stroke (width 0) (type default))
  )
  (wire (pts (xy 224.155 63.5) (xy 205.74 63.5))
    (stroke (width 0) (type default))
  )
  (wire (pts (xy 254.635 78.74) (xy 273.05 78.74))
    (stroke (width 0) (type default))
  )
  (wire (pts (xy 254.635 58.42) (xy 273.05 58.42))
    (stroke (width 0) (type default))
  )
  (wire (pts (xy 224.155 106.68) (xy 205.74 106.68))
    (stroke (width 0) (type default))
  )
  (wire (pts (xy 224.155 73.66) (xy 205.74 73.66))
    (stroke (width 0) (type default))
  )
  (wire (pts (xy 224.155 99.06) (xy 205.74 99.06))
    (stroke (width 0) (type default))
  )
  (wire (pts (xy 105.41 103.505) (xy 86.995 103.505))
    (stroke (width 0) (type default))
  )
  (wire (pts (xy 224.155 91.44) (xy 205.74 91.44))
    (stroke (width 0) (type default))
  )
  (wire (pts (xy 43.18 48.895) (xy 39.37 48.895))
    (stroke (width 0) (type default))
  )
  (wire (pts (xy 219.075 114.3) (xy 219.075 123.825))
    (stroke (width 0) (type default))
  )
  (wire (pts (xy 105.41 113.665) (xy 86.995 113.665))
    (stroke (width 0) (type default))
  )
  (wire (pts (xy 347.345 116.84) (xy 347.345 119.38))
    (stroke (width 0) (type default))
  )
  (wire (pts (xy 334.645 97.79) (xy 340.995 97.79))
    (stroke (width 0) (type default))
  )
  (wire (pts (xy 135.89 65.405) (xy 154.305 65.405))
    (stroke (width 0) (type default))
  )
  (wire (pts (xy 135.89 142.875) (xy 154.305 142.875))
    (stroke (width 0) (type default))
  )
  (wire (pts (xy 347.345 135.89) (xy 347.345 138.43))
    (stroke (width 0) (type default))
  )
  (wire (pts (xy 360.045 97.79) (xy 360.045 100.33))
    (stroke (width 0) (type default))
  )
  (polyline (pts (xy 76.835 214.63) (xy 165.1 214.63))
    (stroke (width 0) (type default))
  )

  (wire (pts (xy 105.41 164.465) (xy 86.995 164.465))
    (stroke (width 0) (type default))
  )
  (wire (pts (xy 105.41 141.605) (xy 86.995 141.605))
    (stroke (width 0) (type default))
  )
  (wire (pts (xy 340.36 77.47) (xy 340.36 80.01))
    (stroke (width 0) (type default))
  )
  (polyline (pts (xy 59.69 39.37) (xy 33.02 39.37))
    (stroke (width 0) (type default))
  )
  (polyline (pts (xy 76.835 181.61) (xy 165.1 181.61))
    (stroke (width 0) (type default))
  )

  (wire (pts (xy 105.41 156.845) (xy 86.995 156.845))
    (stroke (width 0) (type default))
  )
  (wire (pts (xy 105.41 154.305) (xy 86.995 154.305))
    (stroke (width 0) (type default))
  )
  (wire (pts (xy 105.41 95.885) (xy 86.995 95.885))
    (stroke (width 0) (type default))
  )
  (wire (pts (xy 135.89 130.175) (xy 154.305 130.175))
    (stroke (width 0) (type default))
  )
  (wire (pts (xy 105.41 184.785) (xy 86.995 184.785))
    (stroke (width 0) (type default))
  )
  (wire (pts (xy 353.695 116.84) (xy 353.695 119.38))
    (stroke (width 0) (type default))
  )
  (wire (pts (xy 135.89 80.645) (xy 154.305 80.645))
    (stroke (width 0) (type default))
  )
  (wire (pts (xy 135.89 84.455) (xy 154.305 84.455))
    (stroke (width 0) (type default))
  )
  (wire (pts (xy 331.47 135.89) (xy 334.645 135.89))
    (stroke (width 0) (type default))
  )
  (wire (pts (xy 353.695 135.89) (xy 353.695 138.43))
    (stroke (width 0) (type default))
  )
  (wire (pts (xy 135.89 92.075) (xy 154.305 92.075))
    (stroke (width 0) (type default))
  )
  (wire (pts (xy 135.89 89.535) (xy 154.305 89.535))
    (stroke (width 0) (type default))
  )
  (wire (pts (xy 105.41 187.325) (xy 86.995 187.325))
    (stroke (width 0) (type default))
  )
  (wire (pts (xy 135.89 122.555) (xy 154.305 122.555))
    (stroke (width 0) (type default))
  )
  (wire (pts (xy 135.89 107.315) (xy 154.305 107.315))
    (stroke (width 0) (type default))
  )
  (polyline (pts (xy 321.945 48.895) (xy 321.945 173.355))
    (stroke (width 0) (type default))
  )
  (polyline (pts (xy 379.095 173.355) (xy 321.945 173.355))
    (stroke (width 0) (type default))
  )

  (wire (pts (xy 135.89 140.335) (xy 154.305 140.335))
    (stroke (width 0) (type default))
  )
  (wire (pts (xy 105.41 121.285) (xy 86.995 121.285))
    (stroke (width 0) (type default))
  )
  (wire (pts (xy 135.89 86.995) (xy 154.305 86.995))
    (stroke (width 0) (type default))
  )
  (wire (pts (xy 340.995 116.84) (xy 347.345 116.84))
    (stroke (width 0) (type default))
  )
  (wire (pts (xy 254.635 90.17) (xy 273.05 90.17))
    (stroke (width 0) (type default))
  )
  (wire (pts (xy 360.045 116.84) (xy 366.395 116.84))
    (stroke (width 0) (type default))
  )
  (polyline (pts (xy 165.735 189.865) (xy 165.735 214.63))
    (stroke (width 0) (type default))
  )

  (wire (pts (xy 135.89 125.095) (xy 154.305 125.095))
    (stroke (width 0) (type default))
  )
  (wire (pts (xy 224.155 88.9) (xy 205.74 88.9))
    (stroke (width 0) (type default))
  )
  (wire (pts (xy 340.995 135.89) (xy 347.345 135.89))
    (stroke (width 0) (type default))
  )
  (wire (pts (xy 105.41 108.585) (xy 86.995 108.585))
    (stroke (width 0) (type default))
  )
  (wire (pts (xy 105.41 62.865) (xy 86.995 62.865))
    (stroke (width 0) (type default))
  )
  (wire (pts (xy 334.01 57.15) (xy 334.01 59.69))
    (stroke (width 0) (type default))
  )
  (wire (pts (xy 224.155 111.76) (xy 205.74 111.76))
    (stroke (width 0) (type default))
  )
  (wire (pts (xy 135.89 67.945) (xy 154.305 67.945))
    (stroke (width 0) (type default))
  )
  (wire (pts (xy 254.635 100.33) (xy 273.05 100.33))
    (stroke (width 0) (type default))
  )
  (wire (pts (xy 135.89 78.105) (xy 154.305 78.105))
    (stroke (width 0) (type default))
  )
  (wire (pts (xy 346.71 57.15) (xy 353.06 57.15))
    (stroke (width 0) (type default))
  )
  (wire (pts (xy 254.635 60.96) (xy 273.05 60.96))
    (stroke (width 0) (type default))
  )
  (wire (pts (xy 334.01 57.15) (xy 340.36 57.15))
    (stroke (width 0) (type default))
  )
  (wire (pts (xy 330.835 77.47) (xy 334.01 77.47))
    (stroke (width 0) (type default))
  )
  (wire (pts (xy 224.155 101.6) (xy 205.74 101.6))
    (stroke (width 0) (type default))
  )
  (wire (pts (xy 334.645 135.89) (xy 334.645 138.43))
    (stroke (width 0) (type default))
  )
  (wire (pts (xy 105.41 146.685) (xy 86.995 146.685))
    (stroke (width 0) (type default))
  )
  (wire (pts (xy 224.155 96.52) (xy 205.74 96.52))
    (stroke (width 0) (type default))
  )
  (wire (pts (xy 105.41 131.445) (xy 86.995 131.445))
    (stroke (width 0) (type default))
  )
  (wire (pts (xy 254.635 116.84) (xy 273.05 116.84))
    (stroke (width 0) (type default))
  )
  (wire (pts (xy 105.41 128.905) (xy 86.995 128.905))
    (stroke (width 0) (type default))
  )
  (wire (pts (xy 353.695 97.79) (xy 353.695 100.33))
    (stroke (width 0) (type default))
  )
  (wire (pts (xy 135.89 102.235) (xy 154.305 102.235))
    (stroke (width 0) (type default))
  )
  (wire (pts (xy 254.635 85.09) (xy 273.05 85.09))
    (stroke (width 0) (type default))
  )
  (wire (pts (xy 340.36 57.15) (xy 340.36 59.69))
    (stroke (width 0) (type default))
  )
  (wire (pts (xy 340.995 135.89) (xy 340.995 138.43))
    (stroke (width 0) (type default))
  )
  (wire (pts (xy 224.155 86.36) (xy 205.74 86.36))
    (stroke (width 0) (type default))
  )
  (wire (pts (xy 105.41 73.025) (xy 86.995 73.025))
    (stroke (width 0) (type default))
  )
  (wire (pts (xy 210.82 123.825) (xy 210.82 125.095))
    (stroke (width 0) (type default))
  )
  (wire (pts (xy 105.41 200.025) (xy 86.995 200.025))
    (stroke (width 0) (type default))
  )
  (wire (pts (xy 105.41 167.005) (xy 86.995 167.005))
    (stroke (width 0) (type default))
  )
  (wire (pts (xy 330.835 57.15) (xy 334.01 57.15))
    (stroke (width 0) (type default))
  )
  (wire (pts (xy 50.8 48.895) (xy 53.975 48.895))
    (stroke (width 0) (type default))
  )
  (wire (pts (xy 254.635 68.58) (xy 273.05 68.58))
    (stroke (width 0) (type default))
  )
  (wire (pts (xy 222.25 133.35) (xy 224.155 133.35))
    (stroke (width 0) (type default))
  )
  (wire (pts (xy 224.155 81.28) (xy 205.74 81.28))
    (stroke (width 0) (type default))
  )
  (wire (pts (xy 254.635 82.55) (xy 273.05 82.55))
    (stroke (width 0) (type default))
  )
  (wire (pts (xy 254.635 93.98) (xy 273.05 93.98))
    (stroke (width 0) (type default))
  )
  (wire (pts (xy 372.11 77.47) (xy 372.11 80.01))
    (stroke (width 0) (type default))
  )
  (wire (pts (xy 105.41 139.065) (xy 86.995 139.065))
    (stroke (width 0) (type default))
  )
  (wire (pts (xy 105.41 136.525) (xy 86.995 136.525))
    (stroke (width 0) (type default))
  )
  (wire (pts (xy 340.995 155.575) (xy 340.995 158.115))
    (stroke (width 0) (type default))
  )
  (wire (pts (xy 105.41 194.945) (xy 86.995 194.945))
    (stroke (width 0) (type default))
  )
  (wire (pts (xy 205.74 50.8) (xy 224.155 50.8))
    (stroke (width 0) (type default))
  )
  (wire (pts (xy 135.89 99.695) (xy 154.305 99.695))
    (stroke (width 0) (type default))
  )
  (wire (pts (xy 208.28 123.825) (xy 210.82 123.825))
    (stroke (width 0) (type default))
  )
  (wire (pts (xy 105.41 57.785) (xy 86.995 57.785))
    (stroke (width 0) (type default))
  )
  (wire (pts (xy 135.89 109.855) (xy 154.305 109.855))
    (stroke (width 0) (type default))
  )
  (wire (pts (xy 254.635 76.2) (xy 273.05 76.2))
    (stroke (width 0) (type default))
  )
  (wire (pts (xy 366.395 97.79) (xy 366.395 100.33))
    (stroke (width 0) (type default))
  )
  (wire (pts (xy 341.63 238.125) (xy 332.74 238.125))
    (stroke (width 0) (type default))
  )
  (wire (pts (xy 135.89 127.635) (xy 154.305 127.635))
    (stroke (width 0) (type default))
  )
  (wire (pts (xy 334.645 116.84) (xy 334.645 119.38))
    (stroke (width 0) (type default))
  )
  (wire (pts (xy 135.89 104.775) (xy 154.305 104.775))
    (stroke (width 0) (type default))
  )
  (wire (pts (xy 105.41 189.865) (xy 86.995 189.865))
    (stroke (width 0) (type default))
  )
  (wire (pts (xy 224.155 55.88) (xy 205.74 55.88))
    (stroke (width 0) (type default))
  )
  (wire (pts (xy 334.645 135.89) (xy 340.995 135.89))
    (stroke (width 0) (type default))
  )
  (wire (pts (xy 254.635 107.95) (xy 273.05 107.95))
    (stroke (width 0) (type default))
  )
  (wire (pts (xy 224.155 58.42) (xy 205.74 58.42))
    (stroke (width 0) (type default))
  )
  (wire (pts (xy 254.635 119.38) (xy 273.05 119.38))
    (stroke (width 0) (type default))
  )
  (wire (pts (xy 340.36 57.15) (xy 346.71 57.15))
    (stroke (width 0) (type default))
  )
  (wire (pts (xy 360.045 97.79) (xy 366.395 97.79))
    (stroke (width 0) (type default))
  )
  (wire (pts (xy 340.995 97.79) (xy 347.345 97.79))
    (stroke (width 0) (type default))
  )
  (wire (pts (xy 224.155 104.14) (xy 205.74 104.14))
    (stroke (width 0) (type default))
  )
  (wire (pts (xy 353.695 97.79) (xy 360.045 97.79))
    (stroke (width 0) (type default))
  )
  (wire (pts (xy 135.89 168.275) (xy 154.305 168.275))
    (stroke (width 0) (type default))
  )
  (wire (pts (xy 105.41 78.105) (xy 86.995 78.105))
    (stroke (width 0) (type default))
  )
  (wire (pts (xy 105.41 67.945) (xy 86.995 67.945))
    (stroke (width 0) (type default))
  )
  (wire (pts (xy 135.89 62.865) (xy 154.305 62.865))
    (stroke (width 0) (type default))
  )
  (wire (pts (xy 254.635 87.63) (xy 273.05 87.63))
    (stroke (width 0) (type default))
  )
  (wire (pts (xy 135.89 158.115) (xy 154.305 158.115))
    (stroke (width 0) (type default))
  )
  (wire (pts (xy 48.26 48.895) (xy 50.8 48.895))
    (stroke (width 0) (type default))
  )
  (wire (pts (xy 208.28 114.3) (xy 208.28 116.84))
    (stroke (width 0) (type default))
  )
  (wire (pts (xy 347.345 135.89) (xy 353.695 135.89))
    (stroke (width 0) (type default))
  )
  (wire (pts (xy 334.645 155.575) (xy 334.645 158.115))
    (stroke (width 0) (type default))
  )
  (wire (pts (xy 208.28 121.92) (xy 208.28 123.825))
    (stroke (width 0) (type default))
  )
  (wire (pts (xy 254.635 114.3) (xy 273.05 114.3))
    (stroke (width 0) (type default))
  )
  (wire (pts (xy 353.06 77.47) (xy 353.06 80.01))
    (stroke (width 0) (type default))
  )
  (wire (pts (xy 347.345 97.79) (xy 353.695 97.79))
    (stroke (width 0) (type default))
  )
  (wire (pts (xy 205.74 114.3) (xy 208.28 114.3))
    (stroke (width 0) (type default))
  )
  (wire (pts (xy 254.635 53.34) (xy 273.05 53.34))
    (stroke (width 0) (type default))
  )
  (wire (pts (xy 105.41 60.325) (xy 86.995 60.325))
    (stroke (width 0) (type default))
  )
  (wire (pts (xy 105.41 93.345) (xy 86.995 93.345))
    (stroke (width 0) (type default))
  )
  (wire (pts (xy 105.41 179.705) (xy 86.995 179.705))
    (stroke (width 0) (type default))
  )
  (polyline (pts (xy 76.835 82.55) (xy 165.1 82.55))
    (stroke (width 0) (type default))
  )

  (wire (pts (xy 205.74 53.34) (xy 224.155 53.34))
    (stroke (width 0) (type default))
  )
  (wire (pts (xy 105.41 70.485) (xy 86.995 70.485))
    (stroke (width 0) (type default))
  )
  (wire (pts (xy 254.635 96.52) (xy 273.05 96.52))
    (stroke (width 0) (type default))
  )
  (wire (pts (xy 254.635 55.88) (xy 273.05 55.88))
    (stroke (width 0) (type default))
  )
  (wire (pts (xy 105.41 133.985) (xy 86.995 133.985))
    (stroke (width 0) (type default))
  )
  (wire (pts (xy 135.89 70.485) (xy 154.305 70.485))
    (stroke (width 0) (type default))
  )
  (wire (pts (xy 331.47 116.84) (xy 334.645 116.84))
    (stroke (width 0) (type default))
  )
  (wire (pts (xy 135.89 137.795) (xy 154.305 137.795))
    (stroke (width 0) (type default))
  )
  (wire (pts (xy 105.41 111.125) (xy 86.995 111.125))
    (stroke (width 0) (type default))
  )
  (wire (pts (xy 254.635 73.66) (xy 273.05 73.66))
    (stroke (width 0) (type default))
  )
  (wire (pts (xy 359.41 57.15) (xy 365.76 57.15))
    (stroke (width 0) (type default))
  )
  (wire (pts (xy 254.635 105.41) (xy 273.05 105.41))
    (stroke (width 0) (type default))
  )
  (wire (pts (xy 365.76 77.47) (xy 365.76 80.01))
    (stroke (width 0) (type default))
  )
  (wire (pts (xy 135.89 145.415) (xy 154.305 145.415))
    (stroke (width 0) (type default))
  )
  (wire (pts (xy 135.89 75.565) (xy 154.305 75.565))
    (stroke (width 0) (type default))
  )
  (wire (pts (xy 135.89 175.895) (xy 154.305 175.895))
    (stroke (width 0) (type default))
  )
  (wire (pts (xy 224.155 76.2) (xy 205.74 76.2))
    (stroke (width 0) (type default))
  )
  (wire (pts (xy 331.47 155.575) (xy 334.645 155.575))
    (stroke (width 0) (type default))
  )
  (wire (pts (xy 347.345 97.79) (xy 347.345 100.33))
    (stroke (width 0) (type default))
  )
  (wire (pts (xy 105.41 202.565) (xy 86.995 202.565))
    (stroke (width 0) (type default))
  )
  (polyline (pts (xy 165.735 49.53) (xy 165.735 189.865))
    (stroke (width 0) (type default))
  )

  (wire (pts (xy 105.41 88.265) (xy 86.995 88.265))
    (stroke (width 0) (type default))
  )
  (wire (pts (xy 254.635 50.8) (xy 273.05 50.8))
    (stroke (width 0) (type default))
  )
  (wire (pts (xy 105.41 151.765) (xy 86.995 151.765))
    (stroke (width 0) (type default))
  )
  (wire (pts (xy 105.41 75.565) (xy 86.995 75.565))
    (stroke (width 0) (type default))
  )
  (wire (pts (xy 135.89 178.435) (xy 154.305 178.435))
    (stroke (width 0) (type default))
  )
  (wire (pts (xy 346.71 77.47) (xy 346.71 80.01))
    (stroke (width 0) (type default))
  )
  (wire (pts (xy 135.89 60.325) (xy 154.305 60.325))
    (stroke (width 0) (type default))
  )
  (wire (pts (xy 135.89 155.575) (xy 154.305 155.575))
    (stroke (width 0) (type default))
  )
  (wire (pts (xy 135.89 153.035) (xy 154.305 153.035))
    (stroke (width 0) (type default))
  )
  (wire (pts (xy 105.41 144.145) (xy 86.995 144.145))
    (stroke (width 0) (type default))
  )
  (wire (pts (xy 224.155 78.74) (xy 205.74 78.74))
    (stroke (width 0) (type default))
  )
  (wire (pts (xy 347.345 116.84) (xy 353.695 116.84))
    (stroke (width 0) (type default))
  )
  (wire (pts (xy 135.89 135.255) (xy 154.305 135.255))
    (stroke (width 0) (type default))
  )
  (wire (pts (xy 105.41 169.545) (xy 86.995 169.545))
    (stroke (width 0) (type default))
  )
  (wire (pts (xy 105.41 212.725) (xy 86.995 212.725))
    (stroke (width 0) (type default))
  )
  (wire (pts (xy 254.635 66.04) (xy 273.05 66.04))
    (stroke (width 0) (type default))
  )
  (wire (pts (xy 346.71 238.125) (xy 354.965 238.125))
    (stroke (width 0) (type default))
  )
  (wire (pts (xy 254.635 110.49) (xy 273.05 110.49))
    (stroke (width 0) (type default))
  )
  (polyline (pts (xy 76.835 148.59) (xy 165.1 148.59))
    (stroke (width 0) (type default))
  )

  (wire (pts (xy 254.635 125.73) (xy 273.05 125.73))
    (stroke (width 0) (type default))
  )
  (wire (pts (xy 105.41 65.405) (xy 86.995 65.405))
    (stroke (width 0) (type default))
  )
  (wire (pts (xy 105.41 192.405) (xy 86.995 192.405))
    (stroke (width 0) (type default))
  )
  (wire (pts (xy 135.89 163.195) (xy 154.305 163.195))
    (stroke (width 0) (type default))
  )
  (wire (pts (xy 105.41 100.965) (xy 86.995 100.965))
    (stroke (width 0) (type default))
  )
  (wire (pts (xy 353.695 116.84) (xy 360.045 116.84))
    (stroke (width 0) (type default))
  )
  (wire (pts (xy 254.635 123.19) (xy 273.05 123.19))
    (stroke (width 0) (type default))
  )
  (wire (pts (xy 135.89 160.655) (xy 154.305 160.655))
    (stroke (width 0) (type default))
  )
  (wire (pts (xy 224.155 93.98) (xy 205.74 93.98))
    (stroke (width 0) (type default))
  )
  (wire (pts (xy 135.89 150.495) (xy 154.305 150.495))
    (stroke (width 0) (type default))
  )
  (wire (pts (xy 334.01 77.47) (xy 340.36 77.47))
    (stroke (width 0) (type default))
  )
  (wire (pts (xy 105.41 159.385) (xy 86.995 159.385))
    (stroke (width 0) (type default))
  )
  (wire (pts (xy 105.41 177.165) (xy 86.995 177.165))
    (stroke (width 0) (type default))
  )
  (wire (pts (xy 359.41 57.15) (xy 359.41 59.69))
    (stroke (width 0) (type default))
  )
  (polyline (pts (xy 76.2 49.53) (xy 76.2 214.63))
    (stroke (width 0) (type default))
  )

  (wire (pts (xy 135.89 94.615) (xy 154.305 94.615))
    (stroke (width 0) (type default))
  )
  (wire (pts (xy 346.71 57.15) (xy 346.71 59.69))
    (stroke (width 0) (type default))
  )
  (polyline (pts (xy 76.835 49.53) (xy 165.1 49.53))
    (stroke (width 0) (type default))
  )

  (wire (pts (xy 254.635 71.12) (xy 273.05 71.12))
    (stroke (width 0) (type default))
  )
  (wire (pts (xy 334.645 97.79) (xy 334.645 100.33))
    (stroke (width 0) (type default))
  )
  (wire (pts (xy 224.155 83.82) (xy 205.74 83.82))
    (stroke (width 0) (type default))
  )
  (wire (pts (xy 135.89 173.355) (xy 154.305 173.355))
    (stroke (width 0) (type default))
  )
  (wire (pts (xy 105.41 197.485) (xy 86.995 197.485))
    (stroke (width 0) (type default))
  )
  (wire (pts (xy 353.06 57.15) (xy 353.06 59.69))
    (stroke (width 0) (type default))
  )
  (wire (pts (xy 135.89 55.245) (xy 154.305 55.245))
    (stroke (width 0) (type default))
  )
  (wire (pts (xy 365.76 77.47) (xy 372.11 77.47))
    (stroke (width 0) (type default))
  )
  (wire (pts (xy 353.06 77.47) (xy 359.41 77.47))
    (stroke (width 0) (type default))
  )
  (wire (pts (xy 135.89 132.715) (xy 154.305 132.715))
    (stroke (width 0) (type default))
  )
  (wire (pts (xy 135.89 97.155) (xy 154.305 97.155))
    (stroke (width 0) (type default))
  )
  (wire (pts (xy 224.155 71.12) (xy 205.74 71.12))
    (stroke (width 0) (type default))
  )
  (wire (pts (xy 353.06 57.15) (xy 359.41 57.15))
    (stroke (width 0) (type default))
  )
  (wire (pts (xy 135.89 165.735) (xy 154.305 165.735))
    (stroke (width 0) (type default))
  )
  (wire (pts (xy 105.41 126.365) (xy 86.995 126.365))
    (stroke (width 0) (type default))
  )
  (wire (pts (xy 135.89 73.025) (xy 154.305 73.025))
    (stroke (width 0) (type default))
  )
  (wire (pts (xy 105.41 52.705) (xy 86.995 52.705))
    (stroke (width 0) (type default))
  )
  (wire (pts (xy 359.41 77.47) (xy 365.76 77.47))
    (stroke (width 0) (type default))
  )
  (wire (pts (xy 105.41 210.185) (xy 86.995 210.185))
    (stroke (width 0) (type default))
  )
  (polyline (pts (xy 321.945 48.895) (xy 379.095 48.895))
    (stroke (width 0) (type default))
  )

  (wire (pts (xy 105.41 174.625) (xy 86.995 174.625))
    (stroke (width 0) (type default))
  )
  (wire (pts (xy 205.74 123.825) (xy 208.28 123.825))
    (stroke (width 0) (type default))
  )
  (polyline (pts (xy 33.02 52.07) (xy 59.69 52.07))
    (stroke (width 0) (type default))
  )
  (polyline (pts (xy 59.69 52.07) (xy 59.69 39.37))
    (stroke (width 0) (type default))
  )

  (wire (pts (xy 331.47 97.79) (xy 334.645 97.79))
    (stroke (width 0) (type default))
  )
  (wire (pts (xy 340.36 77.47) (xy 346.71 77.47))
    (stroke (width 0) (type default))
  )
  (polyline (pts (xy 165.1 115.57) (xy 76.835 115.57))
    (stroke (width 0) (type default))
  )

  (wire (pts (xy 366.395 116.84) (xy 366.395 119.38))
    (stroke (width 0) (type default))
  )
  (wire (pts (xy 222.25 135.89) (xy 222.25 133.35))
    (stroke (width 0) (type default))
  )
  (wire (pts (xy 219.075 123.825) (xy 210.82 123.825))
    (stroke (width 0) (type default))
  )
  (wire (pts (xy 254.635 63.5) (xy 273.05 63.5))
    (stroke (width 0) (type default))
  )
  (wire (pts (xy 105.41 85.725) (xy 86.995 85.725))
    (stroke (width 0) (type default))
  )
  (wire (pts (xy 224.155 109.22) (xy 205.74 109.22))
    (stroke (width 0) (type default))
  )
  (wire (pts (xy 334.645 116.84) (xy 340.995 116.84))
    (stroke (width 0) (type default))
  )
  (wire (pts (xy 353.695 135.89) (xy 360.045 135.89))
    (stroke (width 0) (type default))
  )
  (wire (pts (xy 50.8 47.625) (xy 50.8 48.895))
    (stroke (width 0) (type default))
  )
  (wire (pts (xy 105.41 205.105) (xy 86.995 205.105))
    (stroke (width 0) (type default))
  )
  (wire (pts (xy 340.995 116.84) (xy 340.995 119.38))
    (stroke (width 0) (type default))
  )
  (wire (pts (xy 360.045 135.89) (xy 360.045 138.43))
    (stroke (width 0) (type default))
  )
  (wire (pts (xy 105.41 161.925) (xy 86.995 161.925))
    (stroke (width 0) (type default))
  )
  (wire (pts (xy 365.76 57.15) (xy 365.76 59.69))
    (stroke (width 0) (type default))
  )
  (wire (pts (xy 359.41 77.47) (xy 359.41 80.01))
    (stroke (width 0) (type default))
  )
  (wire (pts (xy 334.01 77.47) (xy 334.01 80.01))
    (stroke (width 0) (type default))
  )
  (wire (pts (xy 135.89 57.785) (xy 154.305 57.785))
    (stroke (width 0) (type default))
  )
  (wire (pts (xy 105.41 55.245) (xy 86.995 55.245))
    (stroke (width 0) (type default))
  )
  (polyline (pts (xy 33.02 39.37) (xy 33.02 52.07))
    (stroke (width 0) (type default))
  )

  (wire (pts (xy 135.89 52.705) (xy 154.305 52.705))
    (stroke (width 0) (type default))
  )
  (wire (pts (xy 105.41 98.425) (xy 86.995 98.425))
    (stroke (width 0) (type default))
  )
  (wire (pts (xy 224.155 68.58) (xy 205.74 68.58))
    (stroke (width 0) (type default))
  )
  (wire (pts (xy 224.155 60.96) (xy 205.74 60.96))
    (stroke (width 0) (type default))
  )
  (wire (pts (xy 135.89 170.815) (xy 154.305 170.815))
    (stroke (width 0) (type default))
  )
  (wire (pts (xy 340.995 97.79) (xy 340.995 100.33))
    (stroke (width 0) (type default))
  )
  (wire (pts (xy 334.645 155.575) (xy 340.995 155.575))
    (stroke (width 0) (type default))
  )
  (wire (pts (xy 105.41 123.825) (xy 86.995 123.825))
    (stroke (width 0) (type default))
  )
  (wire (pts (xy 254.635 102.87) (xy 273.05 102.87))
    (stroke (width 0) (type default))
  )
  (wire (pts (xy 105.41 118.745) (xy 86.995 118.745))
    (stroke (width 0) (type default))
  )
  (wire (pts (xy 365.76 57.15) (xy 372.11 57.15))
    (stroke (width 0) (type default))
  )
  (wire (pts (xy 105.41 207.645) (xy 86.995 207.645))
    (stroke (width 0) (type default))
  )
  (wire (pts (xy 135.89 112.395) (xy 154.305 112.395))
    (stroke (width 0) (type default))
  )

  (text "2V5 " (at 196.215 61.595 0)
    (effects (font (size 1.27 1.27)) (justify right bottom))
  )
  (text "Place close to the DIMM connector pins" (at 331.47 53.34 0)
    (effects (font (size 1.27 1.27)) (justify left bottom))
  )
  (text "NVRDIMM Backup voltage" (at 34.29 41.91 0)
    (effects (font (size 1.27 1.27)) (justify left bottom))
  )
  (text "DDR4 RDIMM connector" (at 173.99 26.035 0)
    (effects (font (size 2.9972 2.9972) (thickness 0.5994) bold) (justify left bottom))
  )

  (global_label "CB3" (shape input) (at 86.995 192.405 180) (fields_autoplaced)
    (effects (font (size 1.27 1.27)) (justify right))
    (property "Intersheetrefs" "${INTERSHEET_REFS}" (at 80.9213 192.4844 0)
      (effects (font (size 1.27 1.27)) (justify right) hide)
    )
  )
  (global_label "DQ1" (shape input) (at 86.995 55.245 180) (fields_autoplaced)
    (effects (font (size 1.27 1.27)) (justify right))
    (property "Intersheetrefs" "${INTERSHEET_REFS}" (at 80.8608 55.3244 0)
      (effects (font (size 1.27 1.27)) (justify right) hide)
    )
  )
  (global_label "DQS17_N" (shape input) (at 86.995 212.725 180) (fields_autoplaced)
    (effects (font (size 1.27 1.27)) (justify right))
    (property "Intersheetrefs" "${INTERSHEET_REFS}" (at 76.1437 212.6456 0)
      (effects (font (size 1.27 1.27)) (justify right) hide)
    )
  )
  (global_label "DQS16_P" (shape input) (at 154.305 175.895 0) (fields_autoplaced)
    (effects (font (size 1.27 1.27)) (justify left))
    (property "Intersheetrefs" "${INTERSHEET_REFS}" (at 165.0959 175.8156 0)
      (effects (font (size 1.27 1.27)) (justify left) hide)
    )
  )
  (global_label "DQS5_P" (shape input) (at 154.305 104.775 0) (fields_autoplaced)
    (effects (font (size 1.27 1.27)) (justify left))
    (property "Intersheetrefs" "${INTERSHEET_REFS}" (at 163.8863 104.8544 0)
      (effects (font (size 1.27 1.27)) (justify left) hide)
    )
  )
  (global_label "~{WE}\\A14" (shape input) (at 205.74 104.14 180) (fields_autoplaced)
    (effects (font (size 1.27 1.27)) (justify right))
    (property "Intersheetrefs" "${INTERSHEET_REFS}" (at 196.461 104.0606 0)
      (effects (font (size 1.27 1.27)) (justify right) hide)
    )
  )
  (global_label "CKE0" (shape input) (at 273.05 63.5 0) (fields_autoplaced)
    (effects (font (size 1.27 1.27)) (justify left))
    (property "Intersheetrefs" "${INTERSHEET_REFS}" (at 280.2728 63.5794 0)
      (effects (font (size 1.27 1.27)) (justify left) hide)
    )
  )
  (global_label "A0" (shape input) (at 205.74 68.58 180) (fields_autoplaced)
    (effects (font (size 1.27 1.27)) (justify right))
    (property "Intersheetrefs" "${INTERSHEET_REFS}" (at 201.1177 68.5006 0)
      (effects (font (size 1.27 1.27)) (justify right) hide)
    )
  )
  (global_label "CKE1\\NC" (shape input) (at 273.05 66.04 0) (fields_autoplaced)
    (effects (font (size 1.27 1.27)) (justify left))
    (property "Intersheetrefs" "${INTERSHEET_REFS}" (at 283.7199 65.9606 0)
      (effects (font (size 1.27 1.27)) (justify left) hide)
    )
  )
  (global_label "DQ43" (shape input) (at 154.305 92.075 0) (fields_autoplaced)
    (effects (font (size 1.27 1.27)) (justify left))
    (property "Intersheetrefs" "${INTERSHEET_REFS}" (at 161.6487 91.9956 0)
      (effects (font (size 1.27 1.27)) (justify left) hide)
    )
  )
  (global_label "SCL_2V5" (shape input) (at 273.05 125.73 0) (fields_autoplaced)
    (effects (font (size 1.27 1.27)) (justify left))
    (property "Intersheetrefs" "${INTERSHEET_REFS}" (at 283.3571 125.8094 0)
      (effects (font (size 1.27 1.27)) (justify left) hide)
    )
  )
  (global_label "DQ49" (shape input) (at 154.305 120.015 0) (fields_autoplaced)
    (effects (font (size 1.27 1.27)) (justify left))
    (property "Intersheetrefs" "${INTERSHEET_REFS}" (at 161.6487 119.9356 0)
      (effects (font (size 1.27 1.27)) (justify left) hide)
    )
  )
  (global_label "DQS5_N" (shape input) (at 154.305 107.315 0) (fields_autoplaced)
    (effects (font (size 1.27 1.27)) (justify left))
    (property "Intersheetrefs" "${INTERSHEET_REFS}" (at 163.9468 107.3944 0)
      (effects (font (size 1.27 1.27)) (justify left) hide)
    )
  )
  (global_label "DQS0_N" (shape input) (at 86.995 75.565 180) (fields_autoplaced)
    (effects (font (size 1.27 1.27)) (justify right))
    (property "Intersheetrefs" "${INTERSHEET_REFS}" (at 77.3532 75.6444 0)
      (effects (font (size 1.27 1.27)) (justify right) hide)
    )
  )
  (global_label "DQ46" (shape input) (at 154.305 99.695 0) (fields_autoplaced)
    (effects (font (size 1.27 1.27)) (justify left))
    (property "Intersheetrefs" "${INTERSHEET_REFS}" (at 161.6487 99.6156 0)
      (effects (font (size 1.27 1.27)) (justify left) hide)
    )
  )
  (global_label "DQ45" (shape input) (at 154.305 97.155 0) (fields_autoplaced)
    (effects (font (size 1.27 1.27)) (justify left))
    (property "Intersheetrefs" "${INTERSHEET_REFS}" (at 161.6487 97.0756 0)
      (effects (font (size 1.27 1.27)) (justify left) hide)
    )
  )
  (global_label "~{RAS}\\A16" (shape input) (at 205.74 109.22 180) (fields_autoplaced)
    (effects (font (size 1.27 1.27)) (justify right))
    (property "Intersheetrefs" "${INTERSHEET_REFS}" (at 195.4934 109.1406 0)
      (effects (font (size 1.27 1.27)) (justify right) hide)
    )
  )
  (global_label "VTT" (shape input) (at 331.47 155.575 180) (fields_autoplaced)
    (effects (font (size 1.27 1.27)) (justify right))
    (property "Intersheetrefs" "${INTERSHEET_REFS}" (at 326.122 155.6544 0)
      (effects (font (size 1.27 1.27)) (justify right) hide)
    )
  )
  (global_label "DQ7" (shape input) (at 86.995 70.485 180) (fields_autoplaced)
    (effects (font (size 1.27 1.27)) (justify right))
    (property "Intersheetrefs" "${INTERSHEET_REFS}" (at 80.8608 70.5644 0)
      (effects (font (size 1.27 1.27)) (justify right) hide)
    )
  )
  (global_label "DQS11_P" (shape input) (at 86.995 144.145 180) (fields_autoplaced)
    (effects (font (size 1.27 1.27)) (justify right))
    (property "Intersheetrefs" "${INTERSHEET_REFS}" (at 76.2041 144.0656 0)
      (effects (font (size 1.27 1.27)) (justify right) hide)
    )
  )
  (global_label "DQ5" (shape input) (at 86.995 65.405 180) (fields_autoplaced)
    (effects (font (size 1.27 1.27)) (justify right))
    (property "Intersheetrefs" "${INTERSHEET_REFS}" (at 80.8608 65.4844 0)
      (effects (font (size 1.27 1.27)) (justify right) hide)
    )
  )
  (global_label "DQ55" (shape input) (at 154.305 135.255 0) (fields_autoplaced)
    (effects (font (size 1.27 1.27)) (justify left))
    (property "Intersheetrefs" "${INTERSHEET_REFS}" (at 161.6487 135.1756 0)
      (effects (font (size 1.27 1.27)) (justify left) hide)
    )
  )
  (global_label "DQS17_P" (shape input) (at 86.995 210.185 180) (fields_autoplaced)
    (effects (font (size 1.27 1.27)) (justify right))
    (property "Intersheetrefs" "${INTERSHEET_REFS}" (at 76.2041 210.1056 0)
      (effects (font (size 1.27 1.27)) (justify right) hide)
    )
  )
  (global_label "A11" (shape input) (at 205.74 96.52 180) (fields_autoplaced)
    (effects (font (size 1.27 1.27)) (justify right))
    (property "Intersheetrefs" "${INTERSHEET_REFS}" (at 199.9082 96.5994 0)
      (effects (font (size 1.27 1.27)) (justify right) hide)
    )
  )
  (global_label "~{CS2}\\C0" (shape input) (at 273.05 105.41 0) (fields_autoplaced)
    (effects (font (size 1.27 1.27)) (justify left))
    (property "Intersheetrefs" "${INTERSHEET_REFS}" (at 282.3894 105.4894 0)
      (effects (font (size 1.27 1.27)) (justify left) hide)
    )
  )
  (global_label "VPP" (shape input) (at 331.47 135.89 180) (fields_autoplaced)
    (effects (font (size 1.27 1.27)) (justify right))
    (property "Intersheetrefs" "${INTERSHEET_REFS}" (at 325.5172 135.9694 0)
      (effects (font (size 1.27 1.27)) (justify right) hide)
    )
  )
  (global_label "A10\\AP" (shape input) (at 205.74 93.98 180) (fields_autoplaced)
    (effects (font (size 1.27 1.27)) (justify right))
    (property "Intersheetrefs" "${INTERSHEET_REFS}" (at 196.7029 94.0594 0)
      (effects (font (size 1.27 1.27)) (justify right) hide)
    )
  )
  (global_label "DQS2_P" (shape input) (at 86.995 139.065 180) (fields_autoplaced)
    (effects (font (size 1.27 1.27)) (justify right))
    (property "Intersheetrefs" "${INTERSHEET_REFS}" (at 77.4137 139.1444 0)
      (effects (font (size 1.27 1.27)) (justify right) hide)
    )
  )
  (global_label "DQ63" (shape input) (at 154.305 168.275 0) (fields_autoplaced)
    (effects (font (size 1.27 1.27)) (justify left))
    (property "Intersheetrefs" "${INTERSHEET_REFS}" (at 161.6487 168.1956 0)
      (effects (font (size 1.27 1.27)) (justify left) hide)
    )
  )
  (global_label "DQ59" (shape input) (at 154.305 158.115 0) (fields_autoplaced)
    (effects (font (size 1.27 1.27)) (justify left))
    (property "Intersheetrefs" "${INTERSHEET_REFS}" (at 161.6487 158.0356 0)
      (effects (font (size 1.27 1.27)) (justify left) hide)
    )
  )
  (global_label "DQS12_N" (shape input) (at 86.995 179.705 180) (fields_autoplaced)
    (effects (font (size 1.27 1.27)) (justify right))
    (property "Intersheetrefs" "${INTERSHEET_REFS}" (at 76.1437 179.6256 0)
      (effects (font (size 1.27 1.27)) (justify right) hide)
    )
  )
  (global_label "~{ACT}" (shape input) (at 273.05 60.96 0) (fields_autoplaced)
    (effects (font (size 1.27 1.27)) (justify left))
    (property "Intersheetrefs" "${INTERSHEET_REFS}" (at 278.7004 61.0394 0)
      (effects (font (size 1.27 1.27)) (justify left) hide)
    )
  )
  (global_label "CK1_P" (shape input) (at 273.05 87.63 0) (fields_autoplaced)
    (effects (font (size 1.27 1.27)) (justify left))
    (property "Intersheetrefs" "${INTERSHEET_REFS}" (at 281.3613 87.5506 0)
      (effects (font (size 1.27 1.27)) (justify left) hide)
    )
  )
  (global_label "3V3_SYS" (shape input) (at 205.74 114.3 180) (fields_autoplaced)
    (effects (font (size 1.27 1.27)) (justify right))
    (property "Intersheetrefs" "${INTERSHEET_REFS}" (at 195.4329 114.3794 0)
      (effects (font (size 1.27 1.27)) (justify right) hide)
    )
  )
  (global_label "DQ39" (shape input) (at 154.305 70.485 0) (fields_autoplaced)
    (effects (font (size 1.27 1.27)) (justify left))
    (property "Intersheetrefs" "${INTERSHEET_REFS}" (at 161.6487 70.4056 0)
      (effects (font (size 1.27 1.27)) (justify left) hide)
    )
  )
  (global_label "DQ19" (shape input) (at 86.995 126.365 180) (fields_autoplaced)
    (effects (font (size 1.27 1.27)) (justify right))
    (property "Intersheetrefs" "${INTERSHEET_REFS}" (at 79.6513 126.4444 0)
      (effects (font (size 1.27 1.27)) (justify right) hide)
    )
  )
  (global_label "DQ20" (shape input) (at 86.995 128.905 180) (fields_autoplaced)
    (effects (font (size 1.27 1.27)) (justify right))
    (property "Intersheetrefs" "${INTERSHEET_REFS}" (at 79.6513 128.8256 0)
      (effects (font (size 1.27 1.27)) (justify right) hide)
    )
  )
  (global_label "SDA_2V5" (shape input) (at 273.05 123.19 0) (fields_autoplaced)
    (effects (font (size 1.27 1.27)) (justify left))
    (property "Intersheetrefs" "${INTERSHEET_REFS}" (at 283.4175 123.2694 0)
      (effects (font (size 1.27 1.27)) (justify left) hide)
    )
  )
  (global_label "DQ6" (shape input) (at 86.995 67.945 180) (fields_autoplaced)
    (effects (font (size 1.27 1.27)) (justify right))
    (property "Intersheetrefs" "${INTERSHEET_REFS}" (at 80.8608 67.8656 0)
      (effects (font (size 1.27 1.27)) (justify right) hide)
    )
  )
  (global_label "DQ22" (shape input) (at 86.995 133.985 180) (fields_autoplaced)
    (effects (font (size 1.27 1.27)) (justify right))
    (property "Intersheetrefs" "${INTERSHEET_REFS}" (at 79.6513 133.9056 0)
      (effects (font (size 1.27 1.27)) (justify right) hide)
    )
  )
  (global_label "DQS0_P" (shape input) (at 86.995 73.025 180) (fields_autoplaced)
    (effects (font (size 1.27 1.27)) (justify right))
    (property "Intersheetrefs" "${INTERSHEET_REFS}" (at 77.4137 73.1044 0)
      (effects (font (size 1.27 1.27)) (justify right) hide)
    )
  )
  (global_label "CB2" (shape input) (at 86.995 189.865 180) (fields_autoplaced)
    (effects (font (size 1.27 1.27)) (justify right))
    (property "Intersheetrefs" "${INTERSHEET_REFS}" (at 80.9213 189.7856 0)
      (effects (font (size 1.27 1.27)) (justify right) hide)
    )
  )
  (global_label "VDDQ" (shape input) (at 330.835 57.15 180) (fields_autoplaced)
    (effects (font (size 1.27 1.27)) (justify right))
    (property "Intersheetrefs" "${INTERSHEET_REFS}" (at 323.5518 57.2294 0)
      (effects (font (size 1.27 1.27)) (justify right) hide)
    )
  )
  (global_label "DQ16" (shape input) (at 86.995 118.745 180) (fields_autoplaced)
    (effects (font (size 1.27 1.27)) (justify right))
    (property "Intersheetrefs" "${INTERSHEET_REFS}" (at 79.6513 118.6656 0)
      (effects (font (size 1.27 1.27)) (justify right) hide)
    )
  )
  (global_label "A12\\~{BC}" (shape input) (at 205.74 99.06 180) (fields_autoplaced)
    (effects (font (size 1.27 1.27)) (justify right))
    (property "Intersheetrefs" "${INTERSHEET_REFS}" (at 196.5215 98.9806 0)
      (effects (font (size 1.27 1.27)) (justify right) hide)
    )
  )
  (global_label "VDDQ" (shape input) (at 331.47 116.84 180) (fields_autoplaced)
    (effects (font (size 1.27 1.27)) (justify right))
    (property "Intersheetrefs" "${INTERSHEET_REFS}" (at 324.1868 116.9194 0)
      (effects (font (size 1.27 1.27)) (justify right) hide)
    )
  )
  (global_label "DQS4_N" (shape input) (at 154.305 75.565 0) (fields_autoplaced)
    (effects (font (size 1.27 1.27)) (justify left))
    (property "Intersheetrefs" "${INTERSHEET_REFS}" (at 163.9468 75.6444 0)
      (effects (font (size 1.27 1.27)) (justify left) hide)
    )
  )
  (global_label "DQ48" (shape input) (at 154.305 117.475 0) (fields_autoplaced)
    (effects (font (size 1.27 1.27)) (justify left))
    (property "Intersheetrefs" "${INTERSHEET_REFS}" (at 161.6487 117.3956 0)
      (effects (font (size 1.27 1.27)) (justify left) hide)
    )
  )
  (global_label "DQS15_P" (shape input) (at 154.305 142.875 0) (fields_autoplaced)
    (effects (font (size 1.27 1.27)) (justify left))
    (property "Intersheetrefs" "${INTERSHEET_REFS}" (at 165.0959 142.7956 0)
      (effects (font (size 1.27 1.27)) (justify left) hide)
    )
  )
  (global_label "~{CS1}\\NC" (shape input) (at 273.05 102.87 0) (fields_autoplaced)
    (effects (font (size 1.27 1.27)) (justify left))
    (property "Intersheetrefs" "${INTERSHEET_REFS}" (at 282.5104 102.9494 0)
      (effects (font (size 1.27 1.27)) (justify left) hide)
    )
  )
  (global_label "~{CS0}" (shape input) (at 273.05 100.33 0) (fields_autoplaced)
    (effects (font (size 1.27 1.27)) (justify left))
    (property "Intersheetrefs" "${INTERSHEET_REFS}" (at 279.0632 100.4094 0)
      (effects (font (size 1.27 1.27)) (justify left) hide)
    )
  )
  (global_label "VREFCA" (shape input) (at 205.74 58.42 180) (fields_autoplaced)
    (effects (font (size 1.27 1.27)) (justify right))
    (property "Intersheetrefs" "${INTERSHEET_REFS}" (at 196.461 58.4994 0)
      (effects (font (size 1.27 1.27)) (justify right) hide)
    )
  )
  (global_label "CB4" (shape input) (at 86.995 194.945 180) (fields_autoplaced)
    (effects (font (size 1.27 1.27)) (justify right))
    (property "Intersheetrefs" "${INTERSHEET_REFS}" (at 80.9213 194.8656 0)
      (effects (font (size 1.27 1.27)) (justify right) hide)
    )
  )
  (global_label "VDDQ" (shape input) (at 331.47 97.79 180) (fields_autoplaced)
    (effects (font (size 1.27 1.27)) (justify right))
    (property "Intersheetrefs" "${INTERSHEET_REFS}" (at 324.1868 97.8694 0)
      (effects (font (size 1.27 1.27)) (justify right) hide)
    )
  )
  (global_label "DQ10" (shape input) (at 86.995 90.805 180) (fields_autoplaced)
    (effects (font (size 1.27 1.27)) (justify right))
    (property "Intersheetrefs" "${INTERSHEET_REFS}" (at 79.6513 90.7256 0)
      (effects (font (size 1.27 1.27)) (justify right) hide)
    )
  )
  (global_label "~{CAS}\\A15" (shape input) (at 205.74 106.68 180) (fields_autoplaced)
    (effects (font (size 1.27 1.27)) (justify right))
    (property "Intersheetrefs" "${INTERSHEET_REFS}" (at 195.4934 106.6006 0)
      (effects (font (size 1.27 1.27)) (justify right) hide)
    )
  )
  (global_label "DQ23" (shape input) (at 86.995 136.525 180) (fields_autoplaced)
    (effects (font (size 1.27 1.27)) (justify right))
    (property "Intersheetrefs" "${INTERSHEET_REFS}" (at 79.6513 136.6044 0)
      (effects (font (size 1.27 1.27)) (justify right) hide)
    )
  )
  (global_label "A9" (shape input) (at 205.74 91.44 180) (fields_autoplaced)
    (effects (font (size 1.27 1.27)) (justify right))
    (property "Intersheetrefs" "${INTERSHEET_REFS}" (at 201.1177 91.3606 0)
      (effects (font (size 1.27 1.27)) (justify right) hide)
    )
  )
  (global_label "VTT" (shape input) (at 205.74 55.88 180) (fields_autoplaced)
    (effects (font (size 1.27 1.27)) (justify right))
    (property "Intersheetrefs" "${INTERSHEET_REFS}" (at 200.392 55.8006 0)
      (effects (font (size 1.27 1.27)) (justify right) hide)
    )
  )
  (global_label "A1" (shape input) (at 205.74 71.12 180) (fields_autoplaced)
    (effects (font (size 1.27 1.27)) (justify right))
    (property "Intersheetrefs" "${INTERSHEET_REFS}" (at 201.1177 71.0406 0)
      (effects (font (size 1.27 1.27)) (justify right) hide)
    )
  )
  (global_label "DQ54" (shape input) (at 154.305 132.715 0) (fields_autoplaced)
    (effects (font (size 1.27 1.27)) (justify left))
    (property "Intersheetrefs" "${INTERSHEET_REFS}" (at 161.6487 132.6356 0)
      (effects (font (size 1.27 1.27)) (justify left) hide)
    )
  )
  (global_label "A3" (shape input) (at 205.74 76.2 180) (fields_autoplaced)
    (effects (font (size 1.27 1.27)) (justify right))
    (property "Intersheetrefs" "${INTERSHEET_REFS}" (at 201.1177 76.1206 0)
      (effects (font (size 1.27 1.27)) (justify right) hide)
    )
  )
  (global_label "BG1" (shape input) (at 273.05 58.42 0) (fields_autoplaced)
    (effects (font (size 1.27 1.27)) (justify left))
    (property "Intersheetrefs" "${INTERSHEET_REFS}" (at 279.1237 58.3406 0)
      (effects (font (size 1.27 1.27)) (justify left) hide)
    )
  )
  (global_label "DQ31" (shape input) (at 86.995 169.545 180) (fields_autoplaced)
    (effects (font (size 1.27 1.27)) (justify right))
    (property "Intersheetrefs" "${INTERSHEET_REFS}" (at 79.6513 169.6244 0)
      (effects (font (size 1.27 1.27)) (justify right) hide)
    )
  )
  (global_label "PARITY" (shape input) (at 273.05 76.2 0) (fields_autoplaced)
    (effects (font (size 1.27 1.27)) (justify left))
    (property "Intersheetrefs" "${INTERSHEET_REFS}" (at 281.6637 76.1206 0)
      (effects (font (size 1.27 1.27)) (justify left) hide)
    )
  )
  (global_label "DQS9_P" (shape input) (at 86.995 78.105 180) (fields_autoplaced)
    (effects (font (size 1.27 1.27)) (justify right))
    (property "Intersheetrefs" "${INTERSHEET_REFS}" (at 77.4137 78.0256 0)
      (effects (font (size 1.27 1.27)) (justify right) hide)
    )
  )
  (global_label "A2" (shape input) (at 205.74 73.66 180) (fields_autoplaced)
    (effects (font (size 1.27 1.27)) (justify right))
    (property "Intersheetrefs" "${INTERSHEET_REFS}" (at 201.1177 73.7394 0)
      (effects (font (size 1.27 1.27)) (justify right) hide)
    )
  )
  (global_label "A7" (shape input) (at 205.74 86.36 180) (fields_autoplaced)
    (effects (font (size 1.27 1.27)) (justify right))
    (property "Intersheetrefs" "${INTERSHEET_REFS}" (at 201.1177 86.4394 0)
      (effects (font (size 1.27 1.27)) (justify right) hide)
    )
  )
  (global_label "DQ12" (shape input) (at 86.995 95.885 180) (fields_autoplaced)
    (effects (font (size 1.27 1.27)) (justify right))
    (property "Intersheetrefs" "${INTERSHEET_REFS}" (at 79.6513 95.8056 0)
      (effects (font (size 1.27 1.27)) (justify right) hide)
    )
  )
  (global_label "DQ18" (shape input) (at 86.995 123.825 180) (fields_autoplaced)
    (effects (font (size 1.27 1.27)) (justify right))
    (property "Intersheetrefs" "${INTERSHEET_REFS}" (at 79.6513 123.7456 0)
      (effects (font (size 1.27 1.27)) (justify right) hide)
    )
  )
  (global_label "ODT1\\NC" (shape input) (at 273.05 71.12 0) (fields_autoplaced)
    (effects (font (size 1.27 1.27)) (justify left))
    (property "Intersheetrefs" "${INTERSHEET_REFS}" (at 283.599 71.1994 0)
      (effects (font (size 1.27 1.27)) (justify left) hide)
    )
  )
  (global_label "DQ51" (shape input) (at 154.305 125.095 0) (fields_autoplaced)
    (effects (font (size 1.27 1.27)) (justify left))
    (property "Intersheetrefs" "${INTERSHEET_REFS}" (at 161.6487 125.0156 0)
      (effects (font (size 1.27 1.27)) (justify left) hide)
    )
  )
  (global_label "DQS16_N" (shape input) (at 154.305 178.435 0) (fields_autoplaced)
    (effects (font (size 1.27 1.27)) (justify left))
    (property "Intersheetrefs" "${INTERSHEET_REFS}" (at 165.1563 178.3556 0)
      (effects (font (size 1.27 1.27)) (justify left) hide)
    )
  )
  (global_label "A4" (shape input) (at 205.74 78.74 180) (fields_autoplaced)
    (effects (font (size 1.27 1.27)) (justify right))
    (property "Intersheetrefs" "${INTERSHEET_REFS}" (at 201.1177 78.8194 0)
      (effects (font (size 1.27 1.27)) (justify right) hide)
    )
  )
  (global_label "DQ9" (shape input) (at 86.995 88.265 180) (fields_autoplaced)
    (effects (font (size 1.27 1.27)) (justify right))
    (property "Intersheetrefs" "${INTERSHEET_REFS}" (at 80.8608 88.3444 0)
      (effects (font (size 1.27 1.27)) (justify right) hide)
    )
  )
  (global_label "CB7" (shape input) (at 86.995 202.565 180) (fields_autoplaced)
    (effects (font (size 1.27 1.27)) (justify right))
    (property "Intersheetrefs" "${INTERSHEET_REFS}" (at 80.9213 202.6444 0)
      (effects (font (size 1.27 1.27)) (justify right) hide)
    )
  )
  (global_label "VDDSPD" (shape input) (at 354.965 238.125 0) (fields_autoplaced)
    (effects (font (size 1.27 1.27)) (justify left))
    (property "Intersheetrefs" "${INTERSHEET_REFS}" (at 364.6673 238.0456 0)
      (effects (font (size 1.27 1.27)) (justify left) hide)
    )
  )
  (global_label "DQ42" (shape input) (at 154.305 89.535 0) (fields_autoplaced)
    (effects (font (size 1.27 1.27)) (justify left))
    (property "Intersheetrefs" "${INTERSHEET_REFS}" (at 161.6487 89.4556 0)
      (effects (font (size 1.27 1.27)) (justify left) hide)
    )
  )
  (global_label "~{CS3}\\C1,NC" (shape input) (at 273.05 107.95 0) (fields_autoplaced)
    (effects (font (size 1.27 1.27)) (justify left))
    (property "Intersheetrefs" "${INTERSHEET_REFS}" (at 285.5947 108.0294 0)
      (effects (font (size 1.27 1.27)) (justify left) hide)
    )
  )
  (global_label "DQS1_P" (shape input) (at 86.995 106.045 180) (fields_autoplaced)
    (effects (font (size 1.27 1.27)) (justify right))
    (property "Intersheetrefs" "${INTERSHEET_REFS}" (at 77.4137 106.1244 0)
      (effects (font (size 1.27 1.27)) (justify right) hide)
    )
  )
  (global_label "A13" (shape input) (at 205.74 101.6 180) (fields_autoplaced)
    (effects (font (size 1.27 1.27)) (justify right))
    (property "Intersheetrefs" "${INTERSHEET_REFS}" (at 199.9082 101.5206 0)
      (effects (font (size 1.27 1.27)) (justify right) hide)
    )
  )
  (global_label "DQS3_N" (shape input) (at 86.995 174.625 180) (fields_autoplaced)
    (effects (font (size 1.27 1.27)) (justify right))
    (property "Intersheetrefs" "${INTERSHEET_REFS}" (at 77.3532 174.7044 0)
      (effects (font (size 1.27 1.27)) (justify right) hide)
    )
  )
  (global_label "DQS7_P" (shape input) (at 154.305 170.815 0) (fields_autoplaced)
    (effects (font (size 1.27 1.27)) (justify left))
    (property "Intersheetrefs" "${INTERSHEET_REFS}" (at 163.8863 170.8944 0)
      (effects (font (size 1.27 1.27)) (justify left) hide)
    )
  )
  (global_label "DQ24" (shape input) (at 86.995 151.765 180) (fields_autoplaced)
    (effects (font (size 1.27 1.27)) (justify right))
    (property "Intersheetrefs" "${INTERSHEET_REFS}" (at 79.6513 151.6856 0)
      (effects (font (size 1.27 1.27)) (justify right) hide)
    )
  )
  (global_label "A6" (shape input) (at 205.74 83.82 180) (fields_autoplaced)
    (effects (font (size 1.27 1.27)) (justify right))
    (property "Intersheetrefs" "${INTERSHEET_REFS}" (at 201.1177 83.7406 0)
      (effects (font (size 1.27 1.27)) (justify right) hide)
    )
  )
  (global_label "DQ62" (shape input) (at 154.305 165.735 0) (fields_autoplaced)
    (effects (font (size 1.27 1.27)) (justify left))
    (property "Intersheetrefs" "${INTERSHEET_REFS}" (at 161.6487 165.6556 0)
      (effects (font (size 1.27 1.27)) (justify left) hide)
    )
  )
  (global_label "DQ26" (shape input) (at 86.995 156.845 180) (fields_autoplaced)
    (effects (font (size 1.27 1.27)) (justify right))
    (property "Intersheetrefs" "${INTERSHEET_REFS}" (at 79.6513 156.7656 0)
      (effects (font (size 1.27 1.27)) (justify right) hide)
    )
  )
  (global_label "DDR_PRESENCE" (shape input) (at 205.74 123.825 180) (fields_autoplaced)
    (effects (font (size 1.27 1.27)) (justify right))
    (property "Intersheetrefs" "${INTERSHEET_REFS}" (at 188.841 123.7456 0)
      (effects (font (size 1.27 1.27)) (justify right) hide)
    )
  )
  (global_label "~{SAVE}" (shape input) (at 273.05 93.98 0) (fields_autoplaced)
    (effects (font (size 1.27 1.27)) (justify left))
    (property "Intersheetrefs" "${INTERSHEET_REFS}" (at 279.9099 94.0594 0)
      (effects (font (size 1.27 1.27)) (justify left) hide)
    )
  )
  (global_label "DQ4" (shape input) (at 86.995 62.865 180) (fields_autoplaced)
    (effects (font (size 1.27 1.27)) (justify right))
    (property "Intersheetrefs" "${INTERSHEET_REFS}" (at 80.8608 62.7856 0)
      (effects (font (size 1.27 1.27)) (justify right) hide)
    )
  )
  (global_label "DQ11" (shape input) (at 86.995 93.345 180) (fields_autoplaced)
    (effects (font (size 1.27 1.27)) (justify right))
    (property "Intersheetrefs" "${INTERSHEET_REFS}" (at 79.6513 93.4244 0)
      (effects (font (size 1.27 1.27)) (justify right) hide)
    )
  )
  (global_label "CB5" (shape input) (at 86.995 197.485 180) (fields_autoplaced)
    (effects (font (size 1.27 1.27)) (justify right))
    (property "Intersheetrefs" "${INTERSHEET_REFS}" (at 80.9213 197.5644 0)
      (effects (font (size 1.27 1.27)) (justify right) hide)
    )
  )
  (global_label "CK0_N" (shape input) (at 273.05 85.09 0) (fields_autoplaced)
    (effects (font (size 1.27 1.27)) (justify left))
    (property "Intersheetrefs" "${INTERSHEET_REFS}" (at 281.4218 85.0106 0)
      (effects (font (size 1.27 1.27)) (justify left) hide)
    )
  )
  (global_label "DQS9_N" (shape input) (at 86.995 80.645 180) (fields_autoplaced)
    (effects (font (size 1.27 1.27)) (justify right))
    (property "Intersheetrefs" "${INTERSHEET_REFS}" (at 77.3532 80.5656 0)
      (effects (font (size 1.27 1.27)) (justify right) hide)
    )
  )
  (global_label "DQ2" (shape input) (at 86.995 57.785 180) (fields_autoplaced)
    (effects (font (size 1.27 1.27)) (justify right))
    (property "Intersheetrefs" "${INTERSHEET_REFS}" (at 80.8608 57.7056 0)
      (effects (font (size 1.27 1.27)) (justify right) hide)
    )
  )
  (global_label "DQS2_N" (shape input) (at 86.995 141.605 180) (fields_autoplaced)
    (effects (font (size 1.27 1.27)) (justify right))
    (property "Intersheetrefs" "${INTERSHEET_REFS}" (at 77.3532 141.6844 0)
      (effects (font (size 1.27 1.27)) (justify right) hide)
    )
  )
  (global_label "DQS11_N" (shape input) (at 86.995 146.685 180) (fields_autoplaced)
    (effects (font (size 1.27 1.27)) (justify right))
    (property "Intersheetrefs" "${INTERSHEET_REFS}" (at 76.1437 146.6056 0)
      (effects (font (size 1.27 1.27)) (justify right) hide)
    )
  )
  (global_label "DQS8_P" (shape input) (at 86.995 205.105 180) (fields_autoplaced)
    (effects (font (size 1.27 1.27)) (justify right))
    (property "Intersheetrefs" "${INTERSHEET_REFS}" (at 77.4137 205.1844 0)
      (effects (font (size 1.27 1.27)) (justify right) hide)
    )
  )
  (global_label "A8" (shape input) (at 205.74 88.9 180) (fields_autoplaced)
    (effects (font (size 1.27 1.27)) (justify right))
    (property "Intersheetrefs" "${INTERSHEET_REFS}" (at 201.1177 88.8206 0)
      (effects (font (size 1.27 1.27)) (justify right) hide)
    )
  )
  (global_label "DQ27" (shape input) (at 86.995 159.385 180) (fields_autoplaced)
    (effects (font (size 1.27 1.27)) (justify right))
    (property "Intersheetrefs" "${INTERSHEET_REFS}" (at 79.6513 159.4644 0)
      (effects (font (size 1.27 1.27)) (justify right) hide)
    )
  )
  (global_label "~{EVENT}" (shape input) (at 273.05 96.52 0) (fields_autoplaced)
    (effects (font (size 1.27 1.27)) (justify left))
    (property "Intersheetrefs" "${INTERSHEET_REFS}" (at 281.059 96.5994 0)
      (effects (font (size 1.27 1.27)) (justify left) hide)
    )
  )
  (global_label "DQ0" (shape input) (at 86.995 52.705 180) (fields_autoplaced)
    (effects (font (size 1.27 1.27)) (justify right))
    (property "Intersheetrefs" "${INTERSHEET_REFS}" (at 80.8608 52.6256 0)
      (effects (font (size 1.27 1.27)) (justify right) hide)
    )
  )
  (global_label "VPP" (shape input) (at 205.74 63.5 180) (fields_autoplaced)
    (effects (font (size 1.27 1.27)) (justify right))
    (property "Intersheetrefs" "${INTERSHEET_REFS}" (at 199.7872 63.4206 0)
      (effects (font (size 1.27 1.27)) (justify right) hide)
    )
  )
  (global_label "DQS14_P" (shape input) (at 154.305 109.855 0) (fields_autoplaced)
    (effects (font (size 1.27 1.27)) (justify left))
    (property "Intersheetrefs" "${INTERSHEET_REFS}" (at 165.0959 109.7756 0)
      (effects (font (size 1.27 1.27)) (justify left) hide)
    )
  )
  (global_label "DQ8" (shape input) (at 86.995 85.725 180) (fields_autoplaced)
    (effects (font (size 1.27 1.27)) (justify right))
    (property "Intersheetrefs" "${INTERSHEET_REFS}" (at 80.8608 85.6456 0)
      (effects (font (size 1.27 1.27)) (justify right) hide)
    )
  )
  (global_label "DQ28" (shape input) (at 86.995 161.925 180) (fields_autoplaced)
    (effects (font (size 1.27 1.27)) (justify right))
    (property "Intersheetrefs" "${INTERSHEET_REFS}" (at 79.6513 161.8456 0)
      (effects (font (size 1.27 1.27)) (justify right) hide)
    )
  )
  (global_label "DQ52" (shape input) (at 154.305 127.635 0) (fields_autoplaced)
    (effects (font (size 1.27 1.27)) (justify left))
    (property "Intersheetrefs" "${INTERSHEET_REFS}" (at 161.6487 127.5556 0)
      (effects (font (size 1.27 1.27)) (justify left) hide)
    )
  )
  (global_label "DQS13_P" (shape input) (at 154.305 78.105 0) (fields_autoplaced)
    (effects (font (size 1.27 1.27)) (justify left))
    (property "Intersheetrefs" "${INTERSHEET_REFS}" (at 165.0959 78.0256 0)
      (effects (font (size 1.27 1.27)) (justify left) hide)
    )
  )
  (global_label "CK0_P" (shape input) (at 273.05 82.55 0) (fields_autoplaced)
    (effects (font (size 1.27 1.27)) (justify left))
    (property "Intersheetrefs" "${INTERSHEET_REFS}" (at 281.3613 82.4706 0)
      (effects (font (size 1.27 1.27)) (justify left) hide)
    )
  )
  (global_label "DQS12_P" (shape input) (at 86.995 177.165 180) (fields_autoplaced)
    (effects (font (size 1.27 1.27)) (justify right))
    (property "Intersheetrefs" "${INTERSHEET_REFS}" (at 76.2041 177.0856 0)
      (effects (font (size 1.27 1.27)) (justify right) hide)
    )
  )
  (global_label "DQ17" (shape input) (at 86.995 121.285 180) (fields_autoplaced)
    (effects (font (size 1.27 1.27)) (justify right))
    (property "Intersheetrefs" "${INTERSHEET_REFS}" (at 79.6513 121.3644 0)
      (effects (font (size 1.27 1.27)) (justify right) hide)
    )
  )
  (global_label "DQ58" (shape input) (at 154.305 155.575 0) (fields_autoplaced)
    (effects (font (size 1.27 1.27)) (justify left))
    (property "Intersheetrefs" "${INTERSHEET_REFS}" (at 161.6487 155.4956 0)
      (effects (font (size 1.27 1.27)) (justify left) hide)
    )
  )
  (global_label "DQ15" (shape input) (at 86.995 103.505 180) (fields_autoplaced)
    (effects (font (size 1.27 1.27)) (justify right))
    (property "Intersheetrefs" "${INTERSHEET_REFS}" (at 79.6513 103.5844 0)
      (effects (font (size 1.27 1.27)) (justify right) hide)
    )
  )
  (global_label "A5" (shape input) (at 205.74 81.28 180) (fields_autoplaced)
    (effects (font (size 1.27 1.27)) (justify right))
    (property "Intersheetrefs" "${INTERSHEET_REFS}" (at 201.1177 81.3594 0)
      (effects (font (size 1.27 1.27)) (justify right) hide)
    )
  )
  (global_label "VDDQ" (shape input) (at 330.835 77.47 180) (fields_autoplaced)
    (effects (font (size 1.27 1.27)) (justify right))
    (property "Intersheetrefs" "${INTERSHEET_REFS}" (at 323.5518 77.5494 0)
      (effects (font (size 1.27 1.27)) (justify right) hide)
    )
  )
  (global_label "SA2" (shape input) (at 273.05 119.38 0) (fields_autoplaced)
    (effects (font (size 1.27 1.27)) (justify left))
    (property "Intersheetrefs" "${INTERSHEET_REFS}" (at 278.8818 119.4594 0)
      (effects (font (size 1.27 1.27)) (justify left) hide)
    )
  )
  (global_label "DQS4_P" (shape input) (at 154.305 73.025 0) (fields_autoplaced)
    (effects (font (size 1.27 1.27)) (justify left))
    (property "Intersheetrefs" "${INTERSHEET_REFS}" (at 163.8863 73.1044 0)
      (effects (font (size 1.27 1.27)) (justify left) hide)
    )
  )
  (global_label "DQS10_P" (shape input) (at 86.995 111.125 180) (fields_autoplaced)
    (effects (font (size 1.27 1.27)) (justify right))
    (property "Intersheetrefs" "${INTERSHEET_REFS}" (at 76.2041 111.0456 0)
      (effects (font (size 1.27 1.27)) (justify right) hide)
    )
  )
  (global_label "DQ36" (shape input) (at 154.305 62.865 0) (fields_autoplaced)
    (effects (font (size 1.27 1.27)) (justify left))
    (property "Intersheetrefs" "${INTERSHEET_REFS}" (at 161.6487 62.7856 0)
      (effects (font (size 1.27 1.27)) (justify left) hide)
    )
  )
  (global_label "DQS6_N" (shape input) (at 154.305 140.335 0) (fields_autoplaced)
    (effects (font (size 1.27 1.27)) (justify left))
    (property "Intersheetrefs" "${INTERSHEET_REFS}" (at 163.9468 140.4144 0)
      (effects (font (size 1.27 1.27)) (justify left) hide)
    )
  )
  (global_label "DQ14" (shape input) (at 86.995 100.965 180) (fields_autoplaced)
    (effects (font (size 1.27 1.27)) (justify right))
    (property "Intersheetrefs" "${INTERSHEET_REFS}" (at 79.6513 100.8856 0)
      (effects (font (size 1.27 1.27)) (justify right) hide)
    )
  )
  (global_label "CB1" (shape input) (at 86.995 187.325 180) (fields_autoplaced)
    (effects (font (size 1.27 1.27)) (justify right))
    (property "Intersheetrefs" "${INTERSHEET_REFS}" (at 80.9213 187.4044 0)
      (effects (font (size 1.27 1.27)) (justify right) hide)
    )
  )
  (global_label "DQ53" (shape input) (at 154.305 130.175 0) (fields_autoplaced)
    (effects (font (size 1.27 1.27)) (justify left))
    (property "Intersheetrefs" "${INTERSHEET_REFS}" (at 161.6487 130.0956 0)
      (effects (font (size 1.27 1.27)) (justify left) hide)
    )
  )
  (global_label "ODT0" (shape input) (at 273.05 68.58 0) (fields_autoplaced)
    (effects (font (size 1.27 1.27)) (justify left))
    (property "Intersheetrefs" "${INTERSHEET_REFS}" (at 280.1518 68.6594 0)
      (effects (font (size 1.27 1.27)) (justify left) hide)
    )
  )
  (global_label "DQS15_N" (shape input) (at 154.305 145.415 0) (fields_autoplaced)
    (effects (font (size 1.27 1.27)) (justify left))
    (property "Intersheetrefs" "${INTERSHEET_REFS}" (at 165.1563 145.3356 0)
      (effects (font (size 1.27 1.27)) (justify left) hide)
    )
  )
  (global_label "CK1_N" (shape input) (at 273.05 90.17 0) (fields_autoplaced)
    (effects (font (size 1.27 1.27)) (justify left))
    (property "Intersheetrefs" "${INTERSHEET_REFS}" (at 281.4218 90.0906 0)
      (effects (font (size 1.27 1.27)) (justify left) hide)
    )
  )
  (global_label "DQ21" (shape input) (at 86.995 131.445 180) (fields_autoplaced)
    (effects (font (size 1.27 1.27)) (justify right))
    (property "Intersheetrefs" "${INTERSHEET_REFS}" (at 79.6513 131.5244 0)
      (effects (font (size 1.27 1.27)) (justify right) hide)
    )
  )
  (global_label "DQ13" (shape input) (at 86.995 98.425 180) (fields_autoplaced)
    (effects (font (size 1.27 1.27)) (justify right))
    (property "Intersheetrefs" "${INTERSHEET_REFS}" (at 79.6513 98.5044 0)
      (effects (font (size 1.27 1.27)) (justify right) hide)
    )
  )
  (global_label "DQS1_N" (shape input) (at 86.995 108.585 180) (fields_autoplaced)
    (effects (font (size 1.27 1.27)) (justify right))
    (property "Intersheetrefs" "${INTERSHEET_REFS}" (at 77.3532 108.6644 0)
      (effects (font (size 1.27 1.27)) (justify right) hide)
    )
  )
  (global_label "NC\\C2" (shape input) (at 273.05 110.49 0) (fields_autoplaced)
    (effects (font (size 1.27 1.27)) (justify left))
    (property "Intersheetrefs" "${INTERSHEET_REFS}" (at 281.3009 110.5694 0)
      (effects (font (size 1.27 1.27)) (justify left) hide)
    )
  )
  (global_label "DQS14_N" (shape input) (at 154.305 112.395 0) (fields_autoplaced)
    (effects (font (size 1.27 1.27)) (justify left))
    (property "Intersheetrefs" "${INTERSHEET_REFS}" (at 165.1563 112.3156 0)
      (effects (font (size 1.27 1.27)) (justify left) hide)
    )
  )
  (global_label "VIN" (shape input) (at 39.37 48.895 180) (fields_autoplaced)
    (effects (font (size 1.27 1.27)) (justify right))
    (property "Intersheetrefs" "${INTERSHEET_REFS}" (at 34.022 48.8156 0)
      (effects (font (size 1.27 1.27)) (justify right) hide)
    )
  )
  (global_label "DQ57" (shape input) (at 154.305 153.035 0) (fields_autoplaced)
    (effects (font (size 1.27 1.27)) (justify left))
    (property "Intersheetrefs" "${INTERSHEET_REFS}" (at 161.6487 152.9556 0)
      (effects (font (size 1.27 1.27)) (justify left) hide)
    )
  )
  (global_label "VDDSPD" (shape input) (at 205.74 60.96 180) (fields_autoplaced)
    (effects (font (size 1.27 1.27)) (justify right))
    (property "Intersheetrefs" "${INTERSHEET_REFS}" (at 196.0377 60.8806 0)
      (effects (font (size 1.27 1.27)) (justify right) hide)
    )
  )
  (global_label "CB6" (shape input) (at 86.995 200.025 180) (fields_autoplaced)
    (effects (font (size 1.27 1.27)) (justify right))
    (property "Intersheetrefs" "${INTERSHEET_REFS}" (at 80.9213 199.9456 0)
      (effects (font (size 1.27 1.27)) (justify right) hide)
    )
  )
  (global_label "DQS3_P" (shape input) (at 86.995 172.085 180) (fields_autoplaced)
    (effects (font (size 1.27 1.27)) (justify right))
    (property "Intersheetrefs" "${INTERSHEET_REFS}" (at 77.4137 172.1644 0)
      (effects (font (size 1.27 1.27)) (justify right) hide)
    )
  )
  (global_label "VPP" (shape input) (at 332.74 238.125 180) (fields_autoplaced)
    (effects (font (size 1.27 1.27)) (justify right))
    (property "Intersheetrefs" "${INTERSHEET_REFS}" (at 326.7872 238.0456 0)
      (effects (font (size 1.27 1.27)) (justify right) hide)
    )
  )
  (global_label "DQ34" (shape input) (at 154.305 57.785 0) (fields_autoplaced)
    (effects (font (size 1.27 1.27)) (justify left))
    (property "Intersheetrefs" "${INTERSHEET_REFS}" (at 161.6487 57.7056 0)
      (effects (font (size 1.27 1.27)) (justify left) hide)
    )
  )
  (global_label "BG0" (shape input) (at 273.05 55.88 0) (fields_autoplaced)
    (effects (font (size 1.27 1.27)) (justify left))
    (property "Intersheetrefs" "${INTERSHEET_REFS}" (at 279.1237 55.9594 0)
      (effects (font (size 1.27 1.27)) (justify left) hide)
    )
  )
  (global_label "DQS7_N" (shape input) (at 154.305 173.355 0) (fields_autoplaced)
    (effects (font (size 1.27 1.27)) (justify left))
    (property "Intersheetrefs" "${INTERSHEET_REFS}" (at 163.9468 173.4344 0)
      (effects (font (size 1.27 1.27)) (justify left) hide)
    )
  )
  (global_label "DQ61" (shape input) (at 154.305 163.195 0) (fields_autoplaced)
    (effects (font (size 1.27 1.27)) (justify left))
    (property "Intersheetrefs" "${INTERSHEET_REFS}" (at 161.6487 163.1156 0)
      (effects (font (size 1.27 1.27)) (justify left) hide)
    )
  )
  (global_label "NC" (shape input) (at 53.975 48.895 0) (fields_autoplaced)
    (effects (font (size 1.27 1.27)) (justify left))
    (property "Intersheetrefs" "${INTERSHEET_REFS}" (at 58.8997 48.9744 0)
      (effects (font (size 1.27 1.27)) (justify left) hide)
    )
  )
  (global_label "SA0" (shape input) (at 273.05 114.3 0) (fields_autoplaced)
    (effects (font (size 1.27 1.27)) (justify left))
    (property "Intersheetrefs" "${INTERSHEET_REFS}" (at 278.8818 114.2206 0)
      (effects (font (size 1.27 1.27)) (justify left) hide)
    )
  )
  (global_label "DQ35" (shape input) (at 154.305 60.325 0) (fields_autoplaced)
    (effects (font (size 1.27 1.27)) (justify left))
    (property "Intersheetrefs" "${INTERSHEET_REFS}" (at 161.6487 60.2456 0)
      (effects (font (size 1.27 1.27)) (justify left) hide)
    )
  )
  (global_label "DQ56" (shape input) (at 154.305 150.495 0) (fields_autoplaced)
    (effects (font (size 1.27 1.27)) (justify left))
    (property "Intersheetrefs" "${INTERSHEET_REFS}" (at 161.6487 150.4156 0)
      (effects (font (size 1.27 1.27)) (justify left) hide)
    )
  )
  (global_label "DQS8_N" (shape input) (at 86.995 207.645 180) (fields_autoplaced)
    (effects (font (size 1.27 1.27)) (justify right))
    (property "Intersheetrefs" "${INTERSHEET_REFS}" (at 77.3532 207.7244 0)
      (effects (font (size 1.27 1.27)) (justify right) hide)
    )
  )
  (global_label "A17" (shape input) (at 205.74 111.76 180) (fields_autoplaced)
    (effects (font (size 1.27 1.27)) (justify right))
    (property "Intersheetrefs" "${INTERSHEET_REFS}" (at 199.9082 111.6806 0)
      (effects (font (size 1.27 1.27)) (justify right) hide)
    )
  )
  (global_label "DQ32" (shape input) (at 154.305 52.705 0) (fields_autoplaced)
    (effects (font (size 1.27 1.27)) (justify left))
    (property "Intersheetrefs" "${INTERSHEET_REFS}" (at 161.6487 52.6256 0)
      (effects (font (size 1.27 1.27)) (justify left) hide)
    )
  )
  (global_label "DQ47" (shape input) (at 154.305 102.235 0) (fields_autoplaced)
    (effects (font (size 1.27 1.27)) (justify left))
    (property "Intersheetrefs" "${INTERSHEET_REFS}" (at 161.6487 102.1556 0)
      (effects (font (size 1.27 1.27)) (justify left) hide)
    )
  )
  (global_label "DQ60" (shape input) (at 154.305 160.655 0) (fields_autoplaced)
    (effects (font (size 1.27 1.27)) (justify left))
    (property "Intersheetrefs" "${INTERSHEET_REFS}" (at 161.6487 160.5756 0)
      (effects (font (size 1.27 1.27)) (justify left) hide)
    )
  )
  (global_label "DQ25" (shape input) (at 86.995 154.305 180) (fields_autoplaced)
    (effects (font (size 1.27 1.27)) (justify right))
    (property "Intersheetrefs" "${INTERSHEET_REFS}" (at 79.6513 154.3844 0)
      (effects (font (size 1.27 1.27)) (justify right) hide)
    )
  )
  (global_label "DQ41" (shape input) (at 154.305 86.995 0) (fields_autoplaced)
    (effects (font (size 1.27 1.27)) (justify left))
    (property "Intersheetrefs" "${INTERSHEET_REFS}" (at 161.6487 86.9156 0)
      (effects (font (size 1.27 1.27)) (justify left) hide)
    )
  )
  (global_label "DQ30" (shape input) (at 86.995 167.005 180) (fields_autoplaced)
    (effects (font (size 1.27 1.27)) (justify right))
    (property "Intersheetrefs" "${INTERSHEET_REFS}" (at 79.6513 166.9256 0)
      (effects (font (size 1.27 1.27)) (justify right) hide)
    )
  )
  (global_label "DQ37" (shape input) (at 154.305 65.405 0) (fields_autoplaced)
    (effects (font (size 1.27 1.27)) (justify left))
    (property "Intersheetrefs" "${INTERSHEET_REFS}" (at 161.6487 65.3256 0)
      (effects (font (size 1.27 1.27)) (justify left) hide)
    )
  )
  (global_label "DQ33" (shape input) (at 154.305 55.245 0) (fields_autoplaced)
    (effects (font (size 1.27 1.27)) (justify left))
    (property "Intersheetrefs" "${INTERSHEET_REFS}" (at 161.6487 55.1656 0)
      (effects (font (size 1.27 1.27)) (justify left) hide)
    )
  )
  (global_label "DQS10_N" (shape input) (at 86.995 113.665 180) (fields_autoplaced)
    (effects (font (size 1.27 1.27)) (justify right))
    (property "Intersheetrefs" "${INTERSHEET_REFS}" (at 76.1437 113.5856 0)
      (effects (font (size 1.27 1.27)) (justify right) hide)
    )
  )
  (global_label "SA1" (shape input) (at 273.05 116.84 0) (fields_autoplaced)
    (effects (font (size 1.27 1.27)) (justify left))
    (property "Intersheetrefs" "${INTERSHEET_REFS}" (at 278.8818 116.7606 0)
      (effects (font (size 1.27 1.27)) (justify left) hide)
    )
  )
  (global_label "CB0" (shape input) (at 86.995 184.785 180) (fields_autoplaced)
    (effects (font (size 1.27 1.27)) (justify right))
    (property "Intersheetrefs" "${INTERSHEET_REFS}" (at 80.9213 184.7056 0)
      (effects (font (size 1.27 1.27)) (justify right) hide)
    )
  )
  (global_label "DQ29" (shape input) (at 86.995 164.465 180) (fields_autoplaced)
    (effects (font (size 1.27 1.27)) (justify right))
    (property "Intersheetrefs" "${INTERSHEET_REFS}" (at 79.6513 164.5444 0)
      (effects (font (size 1.27 1.27)) (justify right) hide)
    )
  )
  (global_label "~{RESET}" (shape input) (at 273.05 73.66 0) (fields_autoplaced)
    (effects (font (size 1.27 1.27)) (justify left))
    (property "Intersheetrefs" "${INTERSHEET_REFS}" (at 281.1194 73.7394 0)
      (effects (font (size 1.27 1.27)) (justify left) hide)
    )
  )
  (global_label "DQ44" (shape input) (at 154.305 94.615 0) (fields_autoplaced)
    (effects (font (size 1.27 1.27)) (justify left))
    (property "Intersheetrefs" "${INTERSHEET_REFS}" (at 161.6487 94.5356 0)
      (effects (font (size 1.27 1.27)) (justify left) hide)
    )
  )
  (global_label "DQS13_N" (shape input) (at 154.305 80.645 0) (fields_autoplaced)
    (effects (font (size 1.27 1.27)) (justify left))
    (property "Intersheetrefs" "${INTERSHEET_REFS}" (at 165.1563 80.5656 0)
      (effects (font (size 1.27 1.27)) (justify left) hide)
    )
  )
  (global_label "DQ50" (shape input) (at 154.305 122.555 0) (fields_autoplaced)
    (effects (font (size 1.27 1.27)) (justify left))
    (property "Intersheetrefs" "${INTERSHEET_REFS}" (at 161.6487 122.4756 0)
      (effects (font (size 1.27 1.27)) (justify left) hide)
    )
  )
  (global_label "VDDQ" (shape input) (at 205.74 53.34 180) (fields_autoplaced)
    (effects (font (size 1.27 1.27)) (justify right))
    (property "Intersheetrefs" "${INTERSHEET_REFS}" (at 198.4568 53.2606 0)
      (effects (font (size 1.27 1.27)) (justify right) hide)
    )
  )
  (global_label "BA1" (shape input) (at 273.05 53.34 0) (fields_autoplaced)
    (effects (font (size 1.27 1.27)) (justify left))
    (property "Intersheetrefs" "${INTERSHEET_REFS}" (at 278.9423 53.2606 0)
      (effects (font (size 1.27 1.27)) (justify left) hide)
    )
  )
  (global_label "DQ3" (shape input) (at 86.995 60.325 180) (fields_autoplaced)
    (effects (font (size 1.27 1.27)) (justify right))
    (property "Intersheetrefs" "${INTERSHEET_REFS}" (at 80.8608 60.4044 0)
      (effects (font (size 1.27 1.27)) (justify right) hide)
    )
  )
  (global_label "DQS6_P" (shape input) (at 154.305 137.795 0) (fields_autoplaced)
    (effects (font (size 1.27 1.27)) (justify left))
    (property "Intersheetrefs" "${INTERSHEET_REFS}" (at 163.8863 137.8744 0)
      (effects (font (size 1.27 1.27)) (justify left) hide)
    )
  )
  (global_label "BA0" (shape input) (at 273.05 50.8 0) (fields_autoplaced)
    (effects (font (size 1.27 1.27)) (justify left))
    (property "Intersheetrefs" "${INTERSHEET_REFS}" (at 278.9423 50.8794 0)
      (effects (font (size 1.27 1.27)) (justify left) hide)
    )
  )
  (global_label "DQ40" (shape input) (at 154.305 84.455 0) (fields_autoplaced)
    (effects (font (size 1.27 1.27)) (justify left))
    (property "Intersheetrefs" "${INTERSHEET_REFS}" (at 161.6487 84.3756 0)
      (effects (font (size 1.27 1.27)) (justify left) hide)
    )
  )
  (global_label "DQ38" (shape input) (at 154.305 67.945 0) (fields_autoplaced)
    (effects (font (size 1.27 1.27)) (justify left))
    (property "Intersheetrefs" "${INTERSHEET_REFS}" (at 161.6487 67.8656 0)
      (effects (font (size 1.27 1.27)) (justify left) hide)
    )
  )
  (global_label "NC" (shape input) (at 205.74 50.8 180) (fields_autoplaced)
    (effects (font (size 1.27 1.27)) (justify right))
    (property "Intersheetrefs" "${INTERSHEET_REFS}" (at 200.8153 50.7206 0)
      (effects (font (size 1.27 1.27)) (justify right) hide)
    )
  )
  (global_label "~{ALERT}" (shape input) (at 273.05 78.74 0) (fields_autoplaced)
    (effects (font (size 1.27 1.27)) (justify left))
    (property "Intersheetrefs" "${INTERSHEET_REFS}" (at 280.8775 78.6606 0)
      (effects (font (size 1.27 1.27)) (justify left) hide)
    )
  )

  (symbol (lib_id "antmicroTestPoints:TP_1mm_SMD") (at 50.8 47.625 90) (unit 1)
    (in_bom yes) (on_board yes) (dnp no) (fields_autoplaced)
    (property "Reference" "TP10" (at 52.705 44.4499 90)
      (effects (font (size 1.27 1.27)) (justify right))
    )
    (property "Value" "TP_1mm_SMD" (at 58.42 32.385 0)
      (effects (font (size 1.27 1.27) (thickness 0.15)) (justify left bottom) hide)
    )
    (property "Footprint" "antmicro-footprints:TP_SMD_1mm" (at 60.96 32.385 0)
      (effects (font (size 1.27 1.27) (thickness 0.15)) (justify left bottom) hide)
    )
    (property "Datasheet" "" (at 63.5 32.385 0)
      (effects (font (size 1.27 1.27) (thickness 0.15)) (justify left bottom) hide)
    )
    (property "MPN" "" (at 50.8 47.625 0)
      (effects (font (size 1.27 1.27)) hide)
    )
    (property "Manufacturer" "" (at 50.8 47.625 0)
      (effects (font (size 1.27 1.27)) hide)
    )
    (property "Author" "Antmicro" (at 66.04 32.385 0)
      (effects (font (size 1.27 1.27) (thickness 0.15)) (justify left bottom) hide)
    )
    (property "License" "Apache-2.0" (at 68.58 32.385 0)
      (effects (font (size 1.27 1.27) (thickness 0.15)) (justify left bottom) hide)
    )
    (pin "1")
    (instances
      (project "data-center-rdimm-ddr4-tester"
        (path ""
          (reference "TP10") (unit 1)
        )
      )
    )
  )

  (symbol (lib_id "antmicroMemoryConnectorsPCCardSockets:Bus_DDR4_2199155-1") (at 105.41 52.705 0) (unit 1)
    (in_bom yes) (on_board yes) (dnp no) (fields_autoplaced)
    (property "Reference" "U14" (at 120.65 45.085 0)
      (effects (font (size 1.27 1.27)))
    )
    (property "Value" "Bus_DDR4_2199155-1" (at 120.65 47.625 0)
      (effects (font (size 1.27 1.27) (thickness 0.15)))
    )
    (property "Footprint" "antmicro-footprints:Bus_DDR4_Socket_DIMM_2199155-1" (at 154.94 60.325 0)
      (effects (font (size 1.27 1.27) (thickness 0.15)) (justify left bottom) hide)
    )
    (property "Datasheet" "https://www.te.com/usa-en/product-2199155-1.datasheet.pdf" (at 154.94 62.865 0)
      (effects (font (size 1.27 1.27) (thickness 0.15)) (justify left bottom) hide)
    )
    (property "Author" "Antmicro" (at 154.94 65.405 0)
      (effects (font (size 1.27 1.27) (thickness 0.15)) (justify left bottom) hide)
    )
    (property "License" "Apache-2.0" (at 154.94 67.945 0)
      (effects (font (size 1.27 1.27) (thickness 0.15)) (justify left bottom) hide)
    )
    (property "MPN" "2199155-1" (at 105.41 52.705 0)
      (effects (font (size 1.27 1.27)) hide)
    )
    (property "Manufacturer" "TE Connectivity" (at 105.41 52.705 0)
      (effects (font (size 1.27 1.27)) hide)
    )
    (pin "10")
    (pin "100")
    (pin "102")
    (pin "104")
    (pin "106")
    (pin "108")
    (pin "110")
    (pin "111")
    (pin "113")
    (pin "115")
    (pin "117")
    (pin "119")
    (pin "12")
    (pin "121")
    (pin "122")
    (pin "124")
    (pin "126")
    (pin "128")
    (pin "130")
    (pin "132")
    (pin "133")
    (pin "135")
    (pin "137")
    (pin "14")
    (pin "148")
    (pin "150")
    (pin "152")
    (pin "153")
    (pin "155")
    (pin "157")
    (pin "159")
    (pin "16")
    (pin "161")
    (pin "163")
    (pin "164")
    (pin "166")
    (pin "168")
    (pin "170")
    (pin "172")
    (pin "174")
    (pin "175")
    (pin "177")
    (pin "179")
    (pin "18")
    (pin "181")
    (pin "183")
    (pin "185")
    (pin "186")
    (pin "188")
    (pin "19")
    (pin "190")
    (pin "192")
    (pin "194")
    (pin "196")
    (pin "197")
    (pin "199")
    (pin "201")
    (pin "21")
    (pin "23")
    (pin "240")
    (pin "242")
    (pin "244")
    (pin "245")
    (pin "247")
    (pin "249")
    (pin "25")
    (pin "251")
    (pin "253")
    (pin "255")
    (pin "256")
    (pin "258")
    (pin "260")
    (pin "262")
    (pin "264")
    (pin "266")
    (pin "267")
    (pin "269")
    (pin "27")
    (pin "271")
    (pin "273")
    (pin "275")
    (pin "277")
    (pin "278")
    (pin "280")
    (pin "282")
    (pin "29")
    (pin "3")
    (pin "30")
    (pin "32")
    (pin "34")
    (pin "36")
    (pin "38")
    (pin "40")
    (pin "41")
    (pin "43")
    (pin "45")
    (pin "47")
    (pin "49")
    (pin "5")
    (pin "51")
    (pin "52")
    (pin "54")
    (pin "56")
    (pin "7")
    (pin "8")
    (pin "95")
    (pin "97")
    (pin "99")
    (pin "1")
    (pin "101")
    (pin "103")
    (pin "105")
    (pin "107")
    (pin "109")
    (pin "11")
    (pin "112")
    (pin "114")
    (pin "116")
    (pin "118")
    (pin "120")
    (pin "123")
    (pin "125")
    (pin "127")
    (pin "129")
    (pin "13")
    (pin "131")
    (pin "134")
    (pin "136")
    (pin "138")
    (pin "139")
    (pin "140")
    (pin "141")
    (pin "142")
    (pin "143")
    (pin "144")
    (pin "145")
    (pin "146")
    (pin "147")
    (pin "149")
    (pin "15")
    (pin "151")
    (pin "154")
    (pin "156")
    (pin "158")
    (pin "160")
    (pin "162")
    (pin "165")
    (pin "167")
    (pin "169")
    (pin "17")
    (pin "171")
    (pin "173")
    (pin "176")
    (pin "178")
    (pin "180")
    (pin "182")
    (pin "184")
    (pin "187")
    (pin "189")
    (pin "191")
    (pin "193")
    (pin "195")
    (pin "198")
    (pin "2")
    (pin "20")
    (pin "200")
    (pin "202")
    (pin "203")
    (pin "204")
    (pin "205")
    (pin "206")
    (pin "207")
    (pin "208")
    (pin "209")
    (pin "210")
    (pin "211")
    (pin "212")
    (pin "213")
    (pin "214")
    (pin "215")
    (pin "216")
    (pin "217")
    (pin "218")
    (pin "219")
    (pin "22")
    (pin "220")
    (pin "221")
    (pin "222")
    (pin "223")
    (pin "224")
    (pin "225")
    (pin "226")
    (pin "227")
    (pin "228")
    (pin "229")
    (pin "230")
    (pin "231")
    (pin "232")
    (pin "233")
    (pin "234")
    (pin "235")
    (pin "236")
    (pin "237")
    (pin "238")
    (pin "239")
    (pin "24")
    (pin "241")
    (pin "243")
    (pin "246")
    (pin "248")
    (pin "250")
    (pin "252")
    (pin "254")
    (pin "257")
    (pin "259")
    (pin "26")
    (pin "261")
    (pin "263")
    (pin "265")
    (pin "268")
    (pin "270")
    (pin "272")
    (pin "274")
    (pin "276")
    (pin "279")
    (pin "28")
    (pin "281")
    (pin "283")
    (pin "284")
    (pin "285")
    (pin "286")
    (pin "287")
    (pin "288")
    (pin "31")
    (pin "33")
    (pin "35")
    (pin "37")
    (pin "39")
    (pin "4")
    (pin "42")
    (pin "44")
    (pin "46")
    (pin "48")
    (pin "50")
    (pin "53")
    (pin "55")
    (pin "57")
    (pin "58")
    (pin "59")
    (pin "6")
    (pin "60")
    (pin "61")
    (pin "62")
    (pin "63")
    (pin "64")
    (pin "65")
    (pin "66")
    (pin "67")
    (pin "68")
    (pin "69")
    (pin "70")
    (pin "71")
    (pin "72")
    (pin "73")
    (pin "74")
    (pin "75")
    (pin "76")
    (pin "77")
    (pin "78")
    (pin "79")
    (pin "80")
    (pin "81")
    (pin "82")
    (pin "83")
    (pin "84")
    (pin "85")
    (pin "86")
    (pin "87")
    (pin "88")
    (pin "89")
    (pin "9")
    (pin "90")
    (pin "91")
    (pin "92")
    (pin "93")
    (pin "94")
    (pin "96")
    (pin "98")
    (pin "MP1")
    (pin "MP2")
    (pin "MP3")
    (instances
      (project "data-center-rdimm-ddr4-tester"
        (path ""
          (reference "U14") (unit 1)
        )
      )
    )
  )

  (symbol (lib_id "antmicroMemoryConnectorsPCCardSockets:Bus_DDR4_2199155-1") (at 224.155 50.8 0) (unit 2)
    (in_bom yes) (on_board yes) (dnp no) (fields_autoplaced)
    (property "Reference" "U14" (at 239.395 42.545 0)
      (effects (font (size 1.27 1.27)))
    )
    (property "Value" "Bus_DDR4_2199155-1" (at 239.395 45.085 0)
      (effects (font (size 1.27 1.27) (thickness 0.15)))
    )
    (property "Footprint" "antmicro-footprints:Bus_DDR4_Socket_DIMM_2199155-1" (at 273.685 58.42 0)
      (effects (font (size 1.27 1.27) (thickness 0.15)) (justify left bottom) hide)
    )
    (property "Datasheet" "https://www.te.com/usa-en/product-2199155-1.datasheet.pdf" (at 273.685 60.96 0)
      (effects (font (size 1.27 1.27) (thickness 0.15)) (justify left bottom) hide)
    )
    (property "Author" "Antmicro" (at 273.685 63.5 0)
      (effects (font (size 1.27 1.27) (thickness 0.15)) (justify left bottom) hide)
    )
    (property "License" "Apache-2.0" (at 273.685 66.04 0)
      (effects (font (size 1.27 1.27) (thickness 0.15)) (justify left bottom) hide)
    )
    (property "MPN" "2199155-1" (at 224.155 50.8 0)
      (effects (font (size 1.27 1.27)) hide)
    )
    (property "Manufacturer" "TE Connectivity" (at 224.155 50.8 0)
      (effects (font (size 1.27 1.27)) hide)
    )
    (pin "10")
    (pin "100")
    (pin "102")
    (pin "104")
    (pin "106")
    (pin "108")
    (pin "110")
    (pin "111")
    (pin "113")
    (pin "115")
    (pin "117")
    (pin "119")
    (pin "12")
    (pin "121")
    (pin "122")
    (pin "124")
    (pin "126")
    (pin "128")
    (pin "130")
    (pin "132")
    (pin "133")
    (pin "135")
    (pin "137")
    (pin "14")
    (pin "148")
    (pin "150")
    (pin "152")
    (pin "153")
    (pin "155")
    (pin "157")
    (pin "159")
    (pin "16")
    (pin "161")
    (pin "163")
    (pin "164")
    (pin "166")
    (pin "168")
    (pin "170")
    (pin "172")
    (pin "174")
    (pin "175")
    (pin "177")
    (pin "179")
    (pin "18")
    (pin "181")
    (pin "183")
    (pin "185")
    (pin "186")
    (pin "188")
    (pin "19")
    (pin "190")
    (pin "192")
    (pin "194")
    (pin "196")
    (pin "197")
    (pin "199")
    (pin "201")
    (pin "21")
    (pin "23")
    (pin "240")
    (pin "242")
    (pin "244")
    (pin "245")
    (pin "247")
    (pin "249")
    (pin "25")
    (pin "251")
    (pin "253")
    (pin "255")
    (pin "256")
    (pin "258")
    (pin "260")
    (pin "262")
    (pin "264")
    (pin "266")
    (pin "267")
    (pin "269")
    (pin "27")
    (pin "271")
    (pin "273")
    (pin "275")
    (pin "277")
    (pin "278")
    (pin "280")
    (pin "282")
    (pin "29")
    (pin "3")
    (pin "30")
    (pin "32")
    (pin "34")
    (pin "36")
    (pin "38")
    (pin "40")
    (pin "41")
    (pin "43")
    (pin "45")
    (pin "47")
    (pin "49")
    (pin "5")
    (pin "51")
    (pin "52")
    (pin "54")
    (pin "56")
    (pin "7")
    (pin "8")
    (pin "95")
    (pin "97")
    (pin "99")
    (pin "1")
    (pin "101")
    (pin "103")
    (pin "105")
    (pin "107")
    (pin "109")
    (pin "11")
    (pin "112")
    (pin "114")
    (pin "116")
    (pin "118")
    (pin "120")
    (pin "123")
    (pin "125")
    (pin "127")
    (pin "129")
    (pin "13")
    (pin "131")
    (pin "134")
    (pin "136")
    (pin "138")
    (pin "139")
    (pin "140")
    (pin "141")
    (pin "142")
    (pin "143")
    (pin "144")
    (pin "145")
    (pin "146")
    (pin "147")
    (pin "149")
    (pin "15")
    (pin "151")
    (pin "154")
    (pin "156")
    (pin "158")
    (pin "160")
    (pin "162")
    (pin "165")
    (pin "167")
    (pin "169")
    (pin "17")
    (pin "171")
    (pin "173")
    (pin "176")
    (pin "178")
    (pin "180")
    (pin "182")
    (pin "184")
    (pin "187")
    (pin "189")
    (pin "191")
    (pin "193")
    (pin "195")
    (pin "198")
    (pin "2")
    (pin "20")
    (pin "200")
    (pin "202")
    (pin "203")
    (pin "204")
    (pin "205")
    (pin "206")
    (pin "207")
    (pin "208")
    (pin "209")
    (pin "210")
    (pin "211")
    (pin "212")
    (pin "213")
    (pin "214")
    (pin "215")
    (pin "216")
    (pin "217")
    (pin "218")
    (pin "219")
    (pin "22")
    (pin "220")
    (pin "221")
    (pin "222")
    (pin "223")
    (pin "224")
    (pin "225")
    (pin "226")
    (pin "227")
    (pin "228")
    (pin "229")
    (pin "230")
    (pin "231")
    (pin "232")
    (pin "233")
    (pin "234")
    (pin "235")
    (pin "236")
    (pin "237")
    (pin "238")
    (pin "239")
    (pin "24")
    (pin "241")
    (pin "243")
    (pin "246")
    (pin "248")
    (pin "250")
    (pin "252")
    (pin "254")
    (pin "257")
    (pin "259")
    (pin "26")
    (pin "261")
    (pin "263")
    (pin "265")
    (pin "268")
    (pin "270")
    (pin "272")
    (pin "274")
    (pin "276")
    (pin "279")
    (pin "28")
    (pin "281")
    (pin "283")
    (pin "284")
    (pin "285")
    (pin "286")
    (pin "287")
    (pin "288")
    (pin "31")
    (pin "33")
    (pin "35")
    (pin "37")
    (pin "39")
    (pin "4")
    (pin "42")
    (pin "44")
    (pin "46")
    (pin "48")
    (pin "50")
    (pin "53")
    (pin "55")
    (pin "57")
    (pin "58")
    (pin "59")
    (pin "6")
    (pin "60")
    (pin "61")
    (pin "62")
    (pin "63")
    (pin "64")
    (pin "65")
    (pin "66")
    (pin "67")
    (pin "68")
    (pin "69")
    (pin "70")
    (pin "71")
    (pin "72")
    (pin "73")
    (pin "74")
    (pin "75")
    (pin "76")
    (pin "77")
    (pin "78")
    (pin "79")
    (pin "80")
    (pin "81")
    (pin "82")
    (pin "83")
    (pin "84")
    (pin "85")
    (pin "86")
    (pin "87")
    (pin "88")
    (pin "89")
    (pin "9")
    (pin "90")
    (pin "91")
    (pin "92")
    (pin "93")
    (pin "94")
    (pin "96")
    (pin "98")
    (pin "MP1")
    (pin "MP2")
    (pin "MP3")
    (instances
      (project "data-center-rdimm-ddr4-tester"
        (path ""
          (reference "U14") (unit 2)
        )
      )
    )
  )

  (symbol (lib_id "antmicroCapacitors0402:C_100n_0402") (at 359.41 59.69 270) (unit 1)
    (in_bom yes) (on_board yes) (dnp no)
    (property "Reference" "C162" (at 359.41 60.325 90)
      (effects (font (size 1.524 1.524)) (justify left))
    )
    (property "Value" "C_100n_0402" (at 349.25 80.01 0)
      (effects (font (size 1.27 1.27) (thickness 0.15)) (justify left bottom) hide)
    )
    (property "Footprint" "antmicro-footprints:C_0402_1005Metric" (at 346.71 80.01 0)
      (effects (font (size 1.27 1.27) (thickness 0.15)) (justify left bottom) hide)
    )
    (property "Datasheet" "https://search.murata.co.jp/Ceramy/image/img/A01X/G101/ENG/GRM155R61H104KE14-01.pdf" (at 344.17 80.01 0)
      (effects (font (size 1.27 1.27) (thickness 0.15)) (justify left bottom) hide)
    )
    (property "Manufacturer" "Murata" (at 339.09 80.01 0)
      (effects (font (size 1.27 1.27) (thickness 0.15)) (justify left bottom) hide)
    )
    (property "MPN" "GRM155R61H104KE14D" (at 341.63 80.01 0)
      (effects (font (size 1.27 1.27) (thickness 0.15)) (justify left bottom) hide)
    )
    (property "Val" "100n" (at 359.41 64.135 90)
      (effects (font (size 1.27 1.27) (thickness 0.15)) (justify left))
    )
    (property "License" "Apache-2.0" (at 336.55 80.01 0)
      (effects (font (size 1.27 1.27) (thickness 0.15)) (justify left bottom) hide)
    )
    (property "Author" "Antmicro" (at 334.01 80.01 0)
      (effects (font (size 1.27 1.27) (thickness 0.15)) (justify left bottom) hide)
    )
    (property "Voltage" "50V" (at 331.47 80.01 0)
      (effects (font (size 1.27 1.27)) (justify left bottom) hide)
    )
    (property "Dielectric" "X5R" (at 328.93 80.01 0)
      (effects (font (size 1.27 1.27)) (justify left bottom) hide)
    )
    (pin "1")
    (pin "2")
    (instances
      (project "data-center-rdimm-ddr4-tester"
        (path ""
          (reference "C162") (unit 1)
        )
      )
    )
  )

  (symbol (lib_id "antmicroCapacitors0402:C_100n_0402") (at 365.76 59.69 270) (unit 1)
    (in_bom yes) (on_board yes) (dnp no)
    (property "Reference" "C163" (at 365.76 60.325 90)
      (effects (font (size 1.524 1.524)) (justify left))
    )
    (property "Value" "C_100n_0402" (at 355.6 80.01 0)
      (effects (font (size 1.27 1.27) (thickness 0.15)) (justify left bottom) hide)
    )
    (property "Footprint" "antmicro-footprints:C_0402_1005Metric" (at 353.06 80.01 0)
      (effects (font (size 1.27 1.27) (thickness 0.15)) (justify left bottom) hide)
    )
    (property "Datasheet" "https://search.murata.co.jp/Ceramy/image/img/A01X/G101/ENG/GRM155R61H104KE14-01.pdf" (at 350.52 80.01 0)
      (effects (font (size 1.27 1.27) (thickness 0.15)) (justify left bottom) hide)
    )
    (property "Manufacturer" "Murata" (at 345.44 80.01 0)
      (effects (font (size 1.27 1.27) (thickness 0.15)) (justify left bottom) hide)
    )
    (property "MPN" "GRM155R61H104KE14D" (at 347.98 80.01 0)
      (effects (font (size 1.27 1.27) (thickness 0.15)) (justify left bottom) hide)
    )
    (property "Val" "100n" (at 365.76 64.135 90)
      (effects (font (size 1.27 1.27) (thickness 0.15)) (justify left))
    )
    (property "License" "Apache-2.0" (at 342.9 80.01 0)
      (effects (font (size 1.27 1.27) (thickness 0.15)) (justify left bottom) hide)
    )
    (property "Author" "Antmicro" (at 340.36 80.01 0)
      (effects (font (size 1.27 1.27) (thickness 0.15)) (justify left bottom) hide)
    )
    (property "Voltage" "50V" (at 337.82 80.01 0)
      (effects (font (size 1.27 1.27)) (justify left bottom) hide)
    )
    (property "Dielectric" "X5R" (at 335.28 80.01 0)
      (effects (font (size 1.27 1.27)) (justify left bottom) hide)
    )
    (pin "1")
    (pin "2")
    (instances
      (project "data-center-rdimm-ddr4-tester"
        (path ""
          (reference "C163") (unit 1)
        )
      )
    )
  )

  (symbol (lib_id "antmicroCapacitors0402:C_100n_0402") (at 372.11 59.69 270) (unit 1)
    (in_bom yes) (on_board yes) (dnp no)
    (property "Reference" "C164" (at 372.11 60.325 90)
      (effects (font (size 1.524 1.524)) (justify left))
    )
    (property "Value" "C_100n_0402" (at 361.95 80.01 0)
      (effects (font (size 1.27 1.27) (thickness 0.15)) (justify left bottom) hide)
    )
    (property "Footprint" "antmicro-footprints:C_0402_1005Metric" (at 359.41 80.01 0)
      (effects (font (size 1.27 1.27) (thickness 0.15)) (justify left bottom) hide)
    )
    (property "Datasheet" "https://search.murata.co.jp/Ceramy/image/img/A01X/G101/ENG/GRM155R61H104KE14-01.pdf" (at 356.87 80.01 0)
      (effects (font (size 1.27 1.27) (thickness 0.15)) (justify left bottom) hide)
    )
    (property "Manufacturer" "Murata" (at 351.79 80.01 0)
      (effects (font (size 1.27 1.27) (thickness 0.15)) (justify left bottom) hide)
    )
    (property "MPN" "GRM155R61H104KE14D" (at 354.33 80.01 0)
      (effects (font (size 1.27 1.27) (thickness 0.15)) (justify left bottom) hide)
    )
    (property "Val" "100n" (at 372.11 64.135 90)
      (effects (font (size 1.27 1.27) (thickness 0.15)) (justify left))
    )
    (property "License" "Apache-2.0" (at 349.25 80.01 0)
      (effects (font (size 1.27 1.27) (thickness 0.15)) (justify left bottom) hide)
    )
    (property "Author" "Antmicro" (at 346.71 80.01 0)
      (effects (font (size 1.27 1.27) (thickness 0.15)) (justify left bottom) hide)
    )
    (property "Voltage" "50V" (at 344.17 80.01 0)
      (effects (font (size 1.27 1.27)) (justify left bottom) hide)
    )
    (property "Dielectric" "X5R" (at 341.63 80.01 0)
      (effects (font (size 1.27 1.27)) (justify left bottom) hide)
    )
    (pin "1")
    (pin "2")
    (instances
      (project "data-center-rdimm-ddr4-tester"
        (path ""
          (reference "C164") (unit 1)
        )
      )
    )
  )

  (symbol (lib_id "antmicroCapacitors0402:C_100n_0402") (at 334.01 59.69 270) (unit 1)
    (in_bom yes) (on_board yes) (dnp no)
    (property "Reference" "C153" (at 334.01 60.325 90)
      (effects (font (size 1.524 1.524)) (justify left))
    )
    (property "Value" "C_100n_0402" (at 323.85 80.01 0)
      (effects (font (size 1.27 1.27) (thickness 0.15)) (justify left bottom) hide)
    )
    (property "Footprint" "antmicro-footprints:C_0402_1005Metric" (at 321.31 80.01 0)
      (effects (font (size 1.27 1.27) (thickness 0.15)) (justify left bottom) hide)
    )
    (property "Datasheet" "https://search.murata.co.jp/Ceramy/image/img/A01X/G101/ENG/GRM155R61H104KE14-01.pdf" (at 318.77 80.01 0)
      (effects (font (size 1.27 1.27) (thickness 0.15)) (justify left bottom) hide)
    )
    (property "Manufacturer" "Murata" (at 313.69 80.01 0)
      (effects (font (size 1.27 1.27) (thickness 0.15)) (justify left bottom) hide)
    )
    (property "MPN" "GRM155R61H104KE14D" (at 316.23 80.01 0)
      (effects (font (size 1.27 1.27) (thickness 0.15)) (justify left bottom) hide)
    )
    (property "Val" "100n" (at 334.01 64.135 90)
      (effects (font (size 1.27 1.27) (thickness 0.15)) (justify left))
    )
    (property "License" "Apache-2.0" (at 311.15 80.01 0)
      (effects (font (size 1.27 1.27) (thickness 0.15)) (justify left bottom) hide)
    )
    (property "Author" "Antmicro" (at 308.61 80.01 0)
      (effects (font (size 1.27 1.27) (thickness 0.15)) (justify left bottom) hide)
    )
    (property "Voltage" "50V" (at 306.07 80.01 0)
      (effects (font (size 1.27 1.27)) (justify left bottom) hide)
    )
    (property "Dielectric" "X5R" (at 303.53 80.01 0)
      (effects (font (size 1.27 1.27)) (justify left bottom) hide)
    )
    (pin "1")
    (pin "2")
    (instances
      (project "data-center-rdimm-ddr4-tester"
        (path ""
          (reference "C153") (unit 1)
        )
      )
    )
  )

  (symbol (lib_id "antmicroCapacitors0402:C_100n_0402") (at 340.36 59.69 270) (unit 1)
    (in_bom yes) (on_board yes) (dnp no)
    (property "Reference" "C154" (at 340.36 60.325 90)
      (effects (font (size 1.524 1.524)) (justify left))
    )
    (property "Value" "C_100n_0402" (at 330.2 80.01 0)
      (effects (font (size 1.27 1.27) (thickness 0.15)) (justify left bottom) hide)
    )
    (property "Footprint" "antmicro-footprints:C_0402_1005Metric" (at 327.66 80.01 0)
      (effects (font (size 1.27 1.27) (thickness 0.15)) (justify left bottom) hide)
    )
    (property "Datasheet" "https://search.murata.co.jp/Ceramy/image/img/A01X/G101/ENG/GRM155R61H104KE14-01.pdf" (at 325.12 80.01 0)
      (effects (font (size 1.27 1.27) (thickness 0.15)) (justify left bottom) hide)
    )
    (property "Manufacturer" "Murata" (at 320.04 80.01 0)
      (effects (font (size 1.27 1.27) (thickness 0.15)) (justify left bottom) hide)
    )
    (property "MPN" "GRM155R61H104KE14D" (at 322.58 80.01 0)
      (effects (font (size 1.27 1.27) (thickness 0.15)) (justify left bottom) hide)
    )
    (property "Val" "100n" (at 340.36 64.135 90)
      (effects (font (size 1.27 1.27) (thickness 0.15)) (justify left))
    )
    (property "License" "Apache-2.0" (at 317.5 80.01 0)
      (effects (font (size 1.27 1.27) (thickness 0.15)) (justify left bottom) hide)
    )
    (property "Author" "Antmicro" (at 314.96 80.01 0)
      (effects (font (size 1.27 1.27) (thickness 0.15)) (justify left bottom) hide)
    )
    (property "Voltage" "50V" (at 312.42 80.01 0)
      (effects (font (size 1.27 1.27)) (justify left bottom) hide)
    )
    (property "Dielectric" "X5R" (at 309.88 80.01 0)
      (effects (font (size 1.27 1.27)) (justify left bottom) hide)
    )
    (pin "1")
    (pin "2")
    (instances
      (project "data-center-rdimm-ddr4-tester"
        (path ""
          (reference "C154") (unit 1)
        )
      )
    )
  )

  (symbol (lib_id "antmicroCapacitors0402:C_100n_0402") (at 346.71 59.69 270) (unit 1)
    (in_bom yes) (on_board yes) (dnp no)
    (property "Reference" "C160" (at 346.71 60.325 90)
      (effects (font (size 1.524 1.524)) (justify left))
    )
    (property "Value" "C_100n_0402" (at 336.55 80.01 0)
      (effects (font (size 1.27 1.27) (thickness 0.15)) (justify left bottom) hide)
    )
    (property "Footprint" "antmicro-footprints:C_0402_1005Metric" (at 334.01 80.01 0)
      (effects (font (size 1.27 1.27) (thickness 0.15)) (justify left bottom) hide)
    )
    (property "Datasheet" "https://search.murata.co.jp/Ceramy/image/img/A01X/G101/ENG/GRM155R61H104KE14-01.pdf" (at 331.47 80.01 0)
      (effects (font (size 1.27 1.27) (thickness 0.15)) (justify left bottom) hide)
    )
    (property "Manufacturer" "Murata" (at 326.39 80.01 0)
      (effects (font (size 1.27 1.27) (thickness 0.15)) (justify left bottom) hide)
    )
    (property "MPN" "GRM155R61H104KE14D" (at 328.93 80.01 0)
      (effects (font (size 1.27 1.27) (thickness 0.15)) (justify left bottom) hide)
    )
    (property "Val" "100n" (at 346.71 64.135 90)
      (effects (font (size 1.27 1.27) (thickness 0.15)) (justify left))
    )
    (property "License" "Apache-2.0" (at 323.85 80.01 0)
      (effects (font (size 1.27 1.27) (thickness 0.15)) (justify left bottom) hide)
    )
    (property "Author" "Antmicro" (at 321.31 80.01 0)
      (effects (font (size 1.27 1.27) (thickness 0.15)) (justify left bottom) hide)
    )
    (property "Voltage" "50V" (at 318.77 80.01 0)
      (effects (font (size 1.27 1.27)) (justify left bottom) hide)
    )
    (property "Dielectric" "X5R" (at 316.23 80.01 0)
      (effects (font (size 1.27 1.27)) (justify left bottom) hide)
    )
    (pin "1")
    (pin "2")
    (instances
      (project "data-center-rdimm-ddr4-tester"
        (path ""
          (reference "C160") (unit 1)
        )
      )
    )
  )

  (symbol (lib_id "antmicroCapacitors0402:C_100n_0402") (at 353.06 59.69 270) (unit 1)
    (in_bom yes) (on_board yes) (dnp no)
    (property "Reference" "C161" (at 353.06 60.325 90)
      (effects (font (size 1.524 1.524)) (justify left))
    )
    (property "Value" "C_100n_0402" (at 342.9 80.01 0)
      (effects (font (size 1.27 1.27) (thickness 0.15)) (justify left bottom) hide)
    )
    (property "Footprint" "antmicro-footprints:C_0402_1005Metric" (at 340.36 80.01 0)
      (effects (font (size 1.27 1.27) (thickness 0.15)) (justify left bottom) hide)
    )
    (property "Datasheet" "https://search.murata.co.jp/Ceramy/image/img/A01X/G101/ENG/GRM155R61H104KE14-01.pdf" (at 337.82 80.01 0)
      (effects (font (size 1.27 1.27) (thickness 0.15)) (justify left bottom) hide)
    )
    (property "Manufacturer" "Murata" (at 332.74 80.01 0)
      (effects (font (size 1.27 1.27) (thickness 0.15)) (justify left bottom) hide)
    )
    (property "MPN" "GRM155R61H104KE14D" (at 335.28 80.01 0)
      (effects (font (size 1.27 1.27) (thickness 0.15)) (justify left bottom) hide)
    )
    (property "Val" "100n" (at 353.06 64.135 90)
      (effects (font (size 1.27 1.27) (thickness 0.15)) (justify left))
    )
    (property "License" "Apache-2.0" (at 330.2 80.01 0)
      (effects (font (size 1.27 1.27) (thickness 0.15)) (justify left bottom) hide)
    )
    (property "Author" "Antmicro" (at 327.66 80.01 0)
      (effects (font (size 1.27 1.27) (thickness 0.15)) (justify left bottom) hide)
    )
    (property "Voltage" "50V" (at 325.12 80.01 0)
      (effects (font (size 1.27 1.27)) (justify left bottom) hide)
    )
    (property "Dielectric" "X5R" (at 322.58 80.01 0)
      (effects (font (size 1.27 1.27)) (justify left bottom) hide)
    )
    (pin "1")
    (pin "2")
    (instances
      (project "data-center-rdimm-ddr4-tester"
        (path ""
          (reference "C161") (unit 1)
        )
      )
    )
  )

  (symbol (lib_id "antmicropower:GND") (at 334.01 64.77 0) (unit 1)
    (in_bom yes) (on_board yes) (dnp no) (fields_autoplaced)
    (property "Reference" "#PWR0268" (at 334.01 71.12 0)
      (effects (font (size 1.27 1.27)) hide)
    )
    (property "Value" "GND" (at 334.01 69.215 0)
      (effects (font (size 1.27 1.27)))
    )
    (property "Footprint" "" (at 334.01 64.77 0)
      (effects (font (size 1.27 1.27)) hide)
    )
    (property "Datasheet" "" (at 334.01 64.77 0)
      (effects (font (size 1.27 1.27)) hide)
    )
    (property "Author" "Antmicro" (at 342.9 72.39 0)
      (effects (font (size 1.27 1.27) (thickness 0.15)) (justify left bottom) hide)
    )
    (property "License" "Apache-2.0" (at 342.9 74.93 0)
      (effects (font (size 1.27 1.27) (thickness 0.15)) (justify left bottom) hide)
    )
    (pin "1")
    (instances
      (project "data-center-rdimm-ddr4-tester"
        (path ""
          (reference "#PWR0268") (unit 1)
        )
      )
    )
  )

  (symbol (lib_id "antmicropower:GND") (at 340.36 64.77 0) (unit 1)
    (in_bom yes) (on_board yes) (dnp no) (fields_autoplaced)
    (property "Reference" "#PWR0269" (at 340.36 71.12 0)
      (effects (font (size 1.27 1.27)) hide)
    )
    (property "Value" "GND" (at 340.36 69.215 0)
      (effects (font (size 1.27 1.27)))
    )
    (property "Footprint" "" (at 340.36 64.77 0)
      (effects (font (size 1.27 1.27)) hide)
    )
    (property "Datasheet" "" (at 340.36 64.77 0)
      (effects (font (size 1.27 1.27)) hide)
    )
    (property "Author" "Antmicro" (at 349.25 72.39 0)
      (effects (font (size 1.27 1.27) (thickness 0.15)) (justify left bottom) hide)
    )
    (property "License" "Apache-2.0" (at 349.25 74.93 0)
      (effects (font (size 1.27 1.27) (thickness 0.15)) (justify left bottom) hide)
    )
    (pin "1")
    (instances
      (project "data-center-rdimm-ddr4-tester"
        (path ""
          (reference "#PWR0269") (unit 1)
        )
      )
    )
  )

  (symbol (lib_id "antmicropower:GND") (at 346.71 64.77 0) (unit 1)
    (in_bom yes) (on_board yes) (dnp no) (fields_autoplaced)
    (property "Reference" "#PWR0270" (at 346.71 71.12 0)
      (effects (font (size 1.27 1.27)) hide)
    )
    (property "Value" "GND" (at 346.71 69.215 0)
      (effects (font (size 1.27 1.27)))
    )
    (property "Footprint" "" (at 346.71 64.77 0)
      (effects (font (size 1.27 1.27)) hide)
    )
    (property "Datasheet" "" (at 346.71 64.77 0)
      (effects (font (size 1.27 1.27)) hide)
    )
    (property "Author" "Antmicro" (at 355.6 72.39 0)
      (effects (font (size 1.27 1.27) (thickness 0.15)) (justify left bottom) hide)
    )
    (property "License" "Apache-2.0" (at 355.6 74.93 0)
      (effects (font (size 1.27 1.27) (thickness 0.15)) (justify left bottom) hide)
    )
    (pin "1")
    (instances
      (project "data-center-rdimm-ddr4-tester"
        (path ""
          (reference "#PWR0270") (unit 1)
        )
      )
    )
  )

  (symbol (lib_id "antmicropower:GND") (at 353.06 64.77 0) (unit 1)
    (in_bom yes) (on_board yes) (dnp no) (fields_autoplaced)
    (property "Reference" "#PWR0271" (at 353.06 71.12 0)
      (effects (font (size 1.27 1.27)) hide)
    )
    (property "Value" "GND" (at 353.06 69.215 0)
      (effects (font (size 1.27 1.27)))
    )
    (property "Footprint" "" (at 353.06 64.77 0)
      (effects (font (size 1.27 1.27)) hide)
    )
    (property "Datasheet" "" (at 353.06 64.77 0)
      (effects (font (size 1.27 1.27)) hide)
    )
    (property "Author" "Antmicro" (at 361.95 72.39 0)
      (effects (font (size 1.27 1.27) (thickness 0.15)) (justify left bottom) hide)
    )
    (property "License" "Apache-2.0" (at 361.95 74.93 0)
      (effects (font (size 1.27 1.27) (thickness 0.15)) (justify left bottom) hide)
    )
    (pin "1")
    (instances
      (project "data-center-rdimm-ddr4-tester"
        (path ""
          (reference "#PWR0271") (unit 1)
        )
      )
    )
  )

  (symbol (lib_id "antmicropower:GND") (at 359.41 64.77 0) (unit 1)
    (in_bom yes) (on_board yes) (dnp no) (fields_autoplaced)
    (property "Reference" "#PWR0272" (at 359.41 71.12 0)
      (effects (font (size 1.27 1.27)) hide)
    )
    (property "Value" "GND" (at 359.41 69.215 0)
      (effects (font (size 1.27 1.27)))
    )
    (property "Footprint" "" (at 359.41 64.77 0)
      (effects (font (size 1.27 1.27)) hide)
    )
    (property "Datasheet" "" (at 359.41 64.77 0)
      (effects (font (size 1.27 1.27)) hide)
    )
    (property "Author" "Antmicro" (at 368.3 72.39 0)
      (effects (font (size 1.27 1.27) (thickness 0.15)) (justify left bottom) hide)
    )
    (property "License" "Apache-2.0" (at 368.3 74.93 0)
      (effects (font (size 1.27 1.27) (thickness 0.15)) (justify left bottom) hide)
    )
    (pin "1")
    (instances
      (project "data-center-rdimm-ddr4-tester"
        (path ""
          (reference "#PWR0272") (unit 1)
        )
      )
    )
  )

  (symbol (lib_id "antmicropower:GND") (at 365.76 64.77 0) (unit 1)
    (in_bom yes) (on_board yes) (dnp no) (fields_autoplaced)
    (property "Reference" "#PWR0273" (at 365.76 71.12 0)
      (effects (font (size 1.27 1.27)) hide)
    )
    (property "Value" "GND" (at 365.76 69.215 0)
      (effects (font (size 1.27 1.27)))
    )
    (property "Footprint" "" (at 365.76 64.77 0)
      (effects (font (size 1.27 1.27)) hide)
    )
    (property "Datasheet" "" (at 365.76 64.77 0)
      (effects (font (size 1.27 1.27)) hide)
    )
    (property "Author" "Antmicro" (at 374.65 72.39 0)
      (effects (font (size 1.27 1.27) (thickness 0.15)) (justify left bottom) hide)
    )
    (property "License" "Apache-2.0" (at 374.65 74.93 0)
      (effects (font (size 1.27 1.27) (thickness 0.15)) (justify left bottom) hide)
    )
    (pin "1")
    (instances
      (project "data-center-rdimm-ddr4-tester"
        (path ""
          (reference "#PWR0273") (unit 1)
        )
      )
    )
  )

  (symbol (lib_id "antmicropower:GND") (at 372.11 64.77 0) (unit 1)
    (in_bom yes) (on_board yes) (dnp no) (fields_autoplaced)
    (property "Reference" "#PWR0274" (at 372.11 71.12 0)
      (effects (font (size 1.27 1.27)) hide)
    )
    (property "Value" "GND" (at 372.11 69.215 0)
      (effects (font (size 1.27 1.27)))
    )
    (property "Footprint" "" (at 372.11 64.77 0)
      (effects (font (size 1.27 1.27)) hide)
    )
    (property "Datasheet" "" (at 372.11 64.77 0)
      (effects (font (size 1.27 1.27)) hide)
    )
    (property "Author" "Antmicro" (at 381 72.39 0)
      (effects (font (size 1.27 1.27) (thickness 0.15)) (justify left bottom) hide)
    )
    (property "License" "Apache-2.0" (at 381 74.93 0)
      (effects (font (size 1.27 1.27) (thickness 0.15)) (justify left bottom) hide)
    )
    (pin "1")
    (instances
      (project "data-center-rdimm-ddr4-tester"
        (path ""
          (reference "#PWR0274") (unit 1)
        )
      )
    )
  )

  (symbol (lib_id "antmicroCapacitors0402:C_100n_0402") (at 360.045 100.33 270) (unit 1)
    (in_bom yes) (on_board yes) (dnp no)
    (property "Reference" "C169" (at 360.045 100.965 90)
      (effects (font (size 1.524 1.524)) (justify left))
    )
    (property "Value" "C_100n_0402" (at 349.885 120.65 0)
      (effects (font (size 1.27 1.27) (thickness 0.15)) (justify left bottom) hide)
    )
    (property "Footprint" "antmicro-footprints:C_0402_1005Metric" (at 347.345 120.65 0)
      (effects (font (size 1.27 1.27) (thickness 0.15)) (justify left bottom) hide)
    )
    (property "Datasheet" "https://search.murata.co.jp/Ceramy/image/img/A01X/G101/ENG/GRM155R61H104KE14-01.pdf" (at 344.805 120.65 0)
      (effects (font (size 1.27 1.27) (thickness 0.15)) (justify left bottom) hide)
    )
    (property "Manufacturer" "Murata" (at 339.725 120.65 0)
      (effects (font (size 1.27 1.27) (thickness 0.15)) (justify left bottom) hide)
    )
    (property "MPN" "GRM155R61H104KE14D" (at 342.265 120.65 0)
      (effects (font (size 1.27 1.27) (thickness 0.15)) (justify left bottom) hide)
    )
    (property "Val" "100n" (at 360.045 104.775 90)
      (effects (font (size 1.27 1.27) (thickness 0.15)) (justify left))
    )
    (property "License" "Apache-2.0" (at 337.185 120.65 0)
      (effects (font (size 1.27 1.27) (thickness 0.15)) (justify left bottom) hide)
    )
    (property "Author" "Antmicro" (at 334.645 120.65 0)
      (effects (font (size 1.27 1.27) (thickness 0.15)) (justify left bottom) hide)
    )
    (property "Voltage" "50V" (at 332.105 120.65 0)
      (effects (font (size 1.27 1.27)) (justify left bottom) hide)
    )
    (property "Dielectric" "X5R" (at 329.565 120.65 0)
      (effects (font (size 1.27 1.27)) (justify left bottom) hide)
    )
    (pin "1")
    (pin "2")
    (instances
      (project "data-center-rdimm-ddr4-tester"
        (path ""
          (reference "C169") (unit 1)
        )
      )
    )
  )

  (symbol (lib_id "antmicroCapacitors0402:C_100n_0402") (at 366.395 100.33 270) (unit 1)
    (in_bom yes) (on_board yes) (dnp no)
    (property "Reference" "C170" (at 367.03 100.965 90)
      (effects (font (size 1.524 1.524)) (justify left))
    )
    (property "Value" "C_100n_0402" (at 356.235 120.65 0)
      (effects (font (size 1.27 1.27) (thickness 0.15)) (justify left bottom) hide)
    )
    (property "Footprint" "antmicro-footprints:C_0402_1005Metric" (at 353.695 120.65 0)
      (effects (font (size 1.27 1.27) (thickness 0.15)) (justify left bottom) hide)
    )
    (property "Datasheet" "https://search.murata.co.jp/Ceramy/image/img/A01X/G101/ENG/GRM155R61H104KE14-01.pdf" (at 351.155 120.65 0)
      (effects (font (size 1.27 1.27) (thickness 0.15)) (justify left bottom) hide)
    )
    (property "Manufacturer" "Murata" (at 346.075 120.65 0)
      (effects (font (size 1.27 1.27) (thickness 0.15)) (justify left bottom) hide)
    )
    (property "MPN" "GRM155R61H104KE14D" (at 348.615 120.65 0)
      (effects (font (size 1.27 1.27) (thickness 0.15)) (justify left bottom) hide)
    )
    (property "Val" "100n" (at 366.395 104.775 90)
      (effects (font (size 1.27 1.27) (thickness 0.15)) (justify left))
    )
    (property "License" "Apache-2.0" (at 343.535 120.65 0)
      (effects (font (size 1.27 1.27) (thickness 0.15)) (justify left bottom) hide)
    )
    (property "Author" "Antmicro" (at 340.995 120.65 0)
      (effects (font (size 1.27 1.27) (thickness 0.15)) (justify left bottom) hide)
    )
    (property "Voltage" "50V" (at 338.455 120.65 0)
      (effects (font (size 1.27 1.27)) (justify left bottom) hide)
    )
    (property "Dielectric" "X5R" (at 335.915 120.65 0)
      (effects (font (size 1.27 1.27)) (justify left bottom) hide)
    )
    (pin "1")
    (pin "2")
    (instances
      (project "data-center-rdimm-ddr4-tester"
        (path ""
          (reference "C170") (unit 1)
        )
      )
    )
  )

  (symbol (lib_id "antmicroCapacitors0402:C_100n_0402") (at 334.645 100.33 270) (unit 1)
    (in_bom yes) (on_board yes) (dnp no)
    (property "Reference" "C165" (at 334.645 100.965 90)
      (effects (font (size 1.524 1.524)) (justify left))
    )
    (property "Value" "C_100n_0402" (at 324.485 120.65 0)
      (effects (font (size 1.27 1.27) (thickness 0.15)) (justify left bottom) hide)
    )
    (property "Footprint" "antmicro-footprints:C_0402_1005Metric" (at 321.945 120.65 0)
      (effects (font (size 1.27 1.27) (thickness 0.15)) (justify left bottom) hide)
    )
    (property "Datasheet" "https://search.murata.co.jp/Ceramy/image/img/A01X/G101/ENG/GRM155R61H104KE14-01.pdf" (at 319.405 120.65 0)
      (effects (font (size 1.27 1.27) (thickness 0.15)) (justify left bottom) hide)
    )
    (property "Manufacturer" "Murata" (at 314.325 120.65 0)
      (effects (font (size 1.27 1.27) (thickness 0.15)) (justify left bottom) hide)
    )
    (property "MPN" "GRM155R61H104KE14D" (at 316.865 120.65 0)
      (effects (font (size 1.27 1.27) (thickness 0.15)) (justify left bottom) hide)
    )
    (property "Val" "100n" (at 334.645 104.775 90)
      (effects (font (size 1.27 1.27) (thickness 0.15)) (justify left))
    )
    (property "License" "Apache-2.0" (at 311.785 120.65 0)
      (effects (font (size 1.27 1.27) (thickness 0.15)) (justify left bottom) hide)
    )
    (property "Author" "Antmicro" (at 309.245 120.65 0)
      (effects (font (size 1.27 1.27) (thickness 0.15)) (justify left bottom) hide)
    )
    (property "Voltage" "50V" (at 306.705 120.65 0)
      (effects (font (size 1.27 1.27)) (justify left bottom) hide)
    )
    (property "Dielectric" "X5R" (at 304.165 120.65 0)
      (effects (font (size 1.27 1.27)) (justify left bottom) hide)
    )
    (pin "1")
    (pin "2")
    (instances
      (project "data-center-rdimm-ddr4-tester"
        (path ""
          (reference "C165") (unit 1)
        )
      )
    )
  )

  (symbol (lib_id "antmicroCapacitors0402:C_100n_0402") (at 340.995 100.33 270) (unit 1)
    (in_bom yes) (on_board yes) (dnp no)
    (property "Reference" "C166" (at 340.995 100.965 90)
      (effects (font (size 1.524 1.524)) (justify left))
    )
    (property "Value" "C_100n_0402" (at 330.835 120.65 0)
      (effects (font (size 1.27 1.27) (thickness 0.15)) (justify left bottom) hide)
    )
    (property "Footprint" "antmicro-footprints:C_0402_1005Metric" (at 328.295 120.65 0)
      (effects (font (size 1.27 1.27) (thickness 0.15)) (justify left bottom) hide)
    )
    (property "Datasheet" "https://search.murata.co.jp/Ceramy/image/img/A01X/G101/ENG/GRM155R61H104KE14-01.pdf" (at 325.755 120.65 0)
      (effects (font (size 1.27 1.27) (thickness 0.15)) (justify left bottom) hide)
    )
    (property "Manufacturer" "Murata" (at 320.675 120.65 0)
      (effects (font (size 1.27 1.27) (thickness 0.15)) (justify left bottom) hide)
    )
    (property "MPN" "GRM155R61H104KE14D" (at 323.215 120.65 0)
      (effects (font (size 1.27 1.27) (thickness 0.15)) (justify left bottom) hide)
    )
    (property "Val" "100n" (at 340.995 104.775 90)
      (effects (font (size 1.27 1.27) (thickness 0.15)) (justify left))
    )
    (property "License" "Apache-2.0" (at 318.135 120.65 0)
      (effects (font (size 1.27 1.27) (thickness 0.15)) (justify left bottom) hide)
    )
    (property "Author" "Antmicro" (at 315.595 120.65 0)
      (effects (font (size 1.27 1.27) (thickness 0.15)) (justify left bottom) hide)
    )
    (property "Voltage" "50V" (at 313.055 120.65 0)
      (effects (font (size 1.27 1.27)) (justify left bottom) hide)
    )
    (property "Dielectric" "X5R" (at 310.515 120.65 0)
      (effects (font (size 1.27 1.27)) (justify left bottom) hide)
    )
    (pin "1")
    (pin "2")
    (instances
      (project "data-center-rdimm-ddr4-tester"
        (path ""
          (reference "C166") (unit 1)
        )
      )
    )
  )

  (symbol (lib_id "antmicroCapacitors0402:C_100n_0402") (at 347.345 100.33 270) (unit 1)
    (in_bom yes) (on_board yes) (dnp no)
    (property "Reference" "C167" (at 347.345 100.965 90)
      (effects (font (size 1.524 1.524)) (justify left))
    )
    (property "Value" "C_100n_0402" (at 337.185 120.65 0)
      (effects (font (size 1.27 1.27) (thickness 0.15)) (justify left bottom) hide)
    )
    (property "Footprint" "antmicro-footprints:C_0402_1005Metric" (at 334.645 120.65 0)
      (effects (font (size 1.27 1.27) (thickness 0.15)) (justify left bottom) hide)
    )
    (property "Datasheet" "https://search.murata.co.jp/Ceramy/image/img/A01X/G101/ENG/GRM155R61H104KE14-01.pdf" (at 332.105 120.65 0)
      (effects (font (size 1.27 1.27) (thickness 0.15)) (justify left bottom) hide)
    )
    (property "Manufacturer" "Murata" (at 327.025 120.65 0)
      (effects (font (size 1.27 1.27) (thickness 0.15)) (justify left bottom) hide)
    )
    (property "MPN" "GRM155R61H104KE14D" (at 329.565 120.65 0)
      (effects (font (size 1.27 1.27) (thickness 0.15)) (justify left bottom) hide)
    )
    (property "Val" "100n" (at 347.345 104.775 90)
      (effects (font (size 1.27 1.27) (thickness 0.15)) (justify left))
    )
    (property "License" "Apache-2.0" (at 324.485 120.65 0)
      (effects (font (size 1.27 1.27) (thickness 0.15)) (justify left bottom) hide)
    )
    (property "Author" "Antmicro" (at 321.945 120.65 0)
      (effects (font (size 1.27 1.27) (thickness 0.15)) (justify left bottom) hide)
    )
    (property "Voltage" "50V" (at 319.405 120.65 0)
      (effects (font (size 1.27 1.27)) (justify left bottom) hide)
    )
    (property "Dielectric" "X5R" (at 316.865 120.65 0)
      (effects (font (size 1.27 1.27)) (justify left bottom) hide)
    )
    (pin "1")
    (pin "2")
    (instances
      (project "data-center-rdimm-ddr4-tester"
        (path ""
          (reference "C167") (unit 1)
        )
      )
    )
  )

  (symbol (lib_id "antmicroCapacitors0402:C_100n_0402") (at 353.695 100.33 270) (unit 1)
    (in_bom yes) (on_board yes) (dnp no)
    (property "Reference" "C168" (at 353.695 100.965 90)
      (effects (font (size 1.524 1.524)) (justify left))
    )
    (property "Value" "C_100n_0402" (at 343.535 120.65 0)
      (effects (font (size 1.27 1.27) (thickness 0.15)) (justify left bottom) hide)
    )
    (property "Footprint" "antmicro-footprints:C_0402_1005Metric" (at 340.995 120.65 0)
      (effects (font (size 1.27 1.27) (thickness 0.15)) (justify left bottom) hide)
    )
    (property "Datasheet" "https://search.murata.co.jp/Ceramy/image/img/A01X/G101/ENG/GRM155R61H104KE14-01.pdf" (at 338.455 120.65 0)
      (effects (font (size 1.27 1.27) (thickness 0.15)) (justify left bottom) hide)
    )
    (property "Manufacturer" "Murata" (at 333.375 120.65 0)
      (effects (font (size 1.27 1.27) (thickness 0.15)) (justify left bottom) hide)
    )
    (property "MPN" "GRM155R61H104KE14D" (at 335.915 120.65 0)
      (effects (font (size 1.27 1.27) (thickness 0.15)) (justify left bottom) hide)
    )
    (property "Val" "100n" (at 353.695 104.775 90)
      (effects (font (size 1.27 1.27) (thickness 0.15)) (justify left))
    )
    (property "License" "Apache-2.0" (at 330.835 120.65 0)
      (effects (font (size 1.27 1.27) (thickness 0.15)) (justify left bottom) hide)
    )
    (property "Author" "Antmicro" (at 328.295 120.65 0)
      (effects (font (size 1.27 1.27) (thickness 0.15)) (justify left bottom) hide)
    )
    (property "Voltage" "50V" (at 325.755 120.65 0)
      (effects (font (size 1.27 1.27)) (justify left bottom) hide)
    )
    (property "Dielectric" "X5R" (at 323.215 120.65 0)
      (effects (font (size 1.27 1.27)) (justify left bottom) hide)
    )
    (pin "1")
    (pin "2")
    (instances
      (project "data-center-rdimm-ddr4-tester"
        (path ""
          (reference "C168") (unit 1)
        )
      )
    )
  )

  (symbol (lib_id "antmicropower:GND") (at 334.645 105.41 0) (unit 1)
    (in_bom yes) (on_board yes) (dnp no) (fields_autoplaced)
    (property "Reference" "#PWR0275" (at 334.645 111.76 0)
      (effects (font (size 1.27 1.27)) hide)
    )
    (property "Value" "GND" (at 334.645 110.49 0)
      (effects (font (size 1.27 1.27)))
    )
    (property "Footprint" "" (at 334.645 105.41 0)
      (effects (font (size 1.27 1.27)) hide)
    )
    (property "Datasheet" "" (at 334.645 105.41 0)
      (effects (font (size 1.27 1.27)) hide)
    )
    (property "Author" "Antmicro" (at 343.535 113.03 0)
      (effects (font (size 1.27 1.27) (thickness 0.15)) (justify left bottom) hide)
    )
    (property "License" "Apache-2.0" (at 343.535 115.57 0)
      (effects (font (size 1.27 1.27) (thickness 0.15)) (justify left bottom) hide)
    )
    (pin "1")
    (instances
      (project "data-center-rdimm-ddr4-tester"
        (path ""
          (reference "#PWR0275") (unit 1)
        )
      )
    )
  )

  (symbol (lib_id "antmicropower:GND") (at 340.995 105.41 0) (unit 1)
    (in_bom yes) (on_board yes) (dnp no) (fields_autoplaced)
    (property "Reference" "#PWR0276" (at 340.995 111.76 0)
      (effects (font (size 1.27 1.27)) hide)
    )
    (property "Value" "GND" (at 340.995 110.49 0)
      (effects (font (size 1.27 1.27)))
    )
    (property "Footprint" "" (at 340.995 105.41 0)
      (effects (font (size 1.27 1.27)) hide)
    )
    (property "Datasheet" "" (at 340.995 105.41 0)
      (effects (font (size 1.27 1.27)) hide)
    )
    (property "Author" "Antmicro" (at 349.885 113.03 0)
      (effects (font (size 1.27 1.27) (thickness 0.15)) (justify left bottom) hide)
    )
    (property "License" "Apache-2.0" (at 349.885 115.57 0)
      (effects (font (size 1.27 1.27) (thickness 0.15)) (justify left bottom) hide)
    )
    (pin "1")
    (instances
      (project "data-center-rdimm-ddr4-tester"
        (path ""
          (reference "#PWR0276") (unit 1)
        )
      )
    )
  )

  (symbol (lib_id "antmicropower:GND") (at 347.345 105.41 0) (unit 1)
    (in_bom yes) (on_board yes) (dnp no) (fields_autoplaced)
    (property "Reference" "#PWR0277" (at 347.345 111.76 0)
      (effects (font (size 1.27 1.27)) hide)
    )
    (property "Value" "GND" (at 347.345 110.49 0)
      (effects (font (size 1.27 1.27)))
    )
    (property "Footprint" "" (at 347.345 105.41 0)
      (effects (font (size 1.27 1.27)) hide)
    )
    (property "Datasheet" "" (at 347.345 105.41 0)
      (effects (font (size 1.27 1.27)) hide)
    )
    (property "Author" "Antmicro" (at 356.235 113.03 0)
      (effects (font (size 1.27 1.27) (thickness 0.15)) (justify left bottom) hide)
    )
    (property "License" "Apache-2.0" (at 356.235 115.57 0)
      (effects (font (size 1.27 1.27) (thickness 0.15)) (justify left bottom) hide)
    )
    (pin "1")
    (instances
      (project "data-center-rdimm-ddr4-tester"
        (path ""
          (reference "#PWR0277") (unit 1)
        )
      )
    )
  )

  (symbol (lib_id "antmicropower:GND") (at 353.695 105.41 0) (unit 1)
    (in_bom yes) (on_board yes) (dnp no) (fields_autoplaced)
    (property "Reference" "#PWR0278" (at 353.695 111.76 0)
      (effects (font (size 1.27 1.27)) hide)
    )
    (property "Value" "GND" (at 353.695 110.49 0)
      (effects (font (size 1.27 1.27)))
    )
    (property "Footprint" "" (at 353.695 105.41 0)
      (effects (font (size 1.27 1.27)) hide)
    )
    (property "Datasheet" "" (at 353.695 105.41 0)
      (effects (font (size 1.27 1.27)) hide)
    )
    (property "Author" "Antmicro" (at 362.585 113.03 0)
      (effects (font (size 1.27 1.27) (thickness 0.15)) (justify left bottom) hide)
    )
    (property "License" "Apache-2.0" (at 362.585 115.57 0)
      (effects (font (size 1.27 1.27) (thickness 0.15)) (justify left bottom) hide)
    )
    (pin "1")
    (instances
      (project "data-center-rdimm-ddr4-tester"
        (path ""
          (reference "#PWR0278") (unit 1)
        )
      )
    )
  )

  (symbol (lib_id "antmicropower:GND") (at 360.045 105.41 0) (unit 1)
    (in_bom yes) (on_board yes) (dnp no) (fields_autoplaced)
    (property "Reference" "#PWR0279" (at 360.045 111.76 0)
      (effects (font (size 1.27 1.27)) hide)
    )
    (property "Value" "GND" (at 360.045 110.49 0)
      (effects (font (size 1.27 1.27)))
    )
    (property "Footprint" "" (at 360.045 105.41 0)
      (effects (font (size 1.27 1.27)) hide)
    )
    (property "Datasheet" "" (at 360.045 105.41 0)
      (effects (font (size 1.27 1.27)) hide)
    )
    (property "Author" "Antmicro" (at 368.935 113.03 0)
      (effects (font (size 1.27 1.27) (thickness 0.15)) (justify left bottom) hide)
    )
    (property "License" "Apache-2.0" (at 368.935 115.57 0)
      (effects (font (size 1.27 1.27) (thickness 0.15)) (justify left bottom) hide)
    )
    (pin "1")
    (instances
      (project "data-center-rdimm-ddr4-tester"
        (path ""
          (reference "#PWR0279") (unit 1)
        )
      )
    )
  )

  (symbol (lib_id "antmicropower:GND") (at 366.395 105.41 0) (unit 1)
    (in_bom yes) (on_board yes) (dnp no) (fields_autoplaced)
    (property "Reference" "#PWR0280" (at 366.395 111.76 0)
      (effects (font (size 1.27 1.27)) hide)
    )
    (property "Value" "GND" (at 366.395 110.49 0)
      (effects (font (size 1.27 1.27)))
    )
    (property "Footprint" "" (at 366.395 105.41 0)
      (effects (font (size 1.27 1.27)) hide)
    )
    (property "Datasheet" "" (at 366.395 105.41 0)
      (effects (font (size 1.27 1.27)) hide)
    )
    (property "Author" "Antmicro" (at 375.285 113.03 0)
      (effects (font (size 1.27 1.27) (thickness 0.15)) (justify left bottom) hide)
    )
    (property "License" "Apache-2.0" (at 375.285 115.57 0)
      (effects (font (size 1.27 1.27) (thickness 0.15)) (justify left bottom) hide)
    )
    (pin "1")
    (instances
      (project "data-center-rdimm-ddr4-tester"
        (path ""
          (reference "#PWR0280") (unit 1)
        )
      )
    )
  )

  (symbol (lib_id "antmicroCapacitors0402:C_100n_0402") (at 360.045 119.38 270) (unit 1)
    (in_bom yes) (on_board yes) (dnp no)
    (property "Reference" "C179" (at 360.045 120.015 90)
      (effects (font (size 1.524 1.524)) (justify left))
    )
    (property "Value" "C_100n_0402" (at 349.885 139.7 0)
      (effects (font (size 1.27 1.27) (thickness 0.15)) (justify left bottom) hide)
    )
    (property "Footprint" "antmicro-footprints:C_0402_1005Metric" (at 347.345 139.7 0)
      (effects (font (size 1.27 1.27) (thickness 0.15)) (justify left bottom) hide)
    )
    (property "Datasheet" "https://search.murata.co.jp/Ceramy/image/img/A01X/G101/ENG/GRM155R61H104KE14-01.pdf" (at 344.805 139.7 0)
      (effects (font (size 1.27 1.27) (thickness 0.15)) (justify left bottom) hide)
    )
    (property "Manufacturer" "Murata" (at 339.725 139.7 0)
      (effects (font (size 1.27 1.27) (thickness 0.15)) (justify left bottom) hide)
    )
    (property "MPN" "GRM155R61H104KE14D" (at 342.265 139.7 0)
      (effects (font (size 1.27 1.27) (thickness 0.15)) (justify left bottom) hide)
    )
    (property "Val" "100n" (at 360.045 123.825 90)
      (effects (font (size 1.27 1.27) (thickness 0.15)) (justify left))
    )
    (property "License" "Apache-2.0" (at 337.185 139.7 0)
      (effects (font (size 1.27 1.27) (thickness 0.15)) (justify left bottom) hide)
    )
    (property "Author" "Antmicro" (at 334.645 139.7 0)
      (effects (font (size 1.27 1.27) (thickness 0.15)) (justify left bottom) hide)
    )
    (property "Voltage" "50V" (at 332.105 139.7 0)
      (effects (font (size 1.27 1.27)) (justify left bottom) hide)
    )
    (property "Dielectric" "X5R" (at 329.565 139.7 0)
      (effects (font (size 1.27 1.27)) (justify left bottom) hide)
    )
    (pin "1")
    (pin "2")
    (instances
      (project "data-center-rdimm-ddr4-tester"
        (path ""
          (reference "C179") (unit 1)
        )
      )
    )
  )

  (symbol (lib_id "antmicroCapacitors0402:C_100n_0402") (at 366.395 119.38 270) (unit 1)
    (in_bom yes) (on_board yes) (dnp no)
    (property "Reference" "C181" (at 366.395 120.015 90)
      (effects (font (size 1.524 1.524)) (justify left))
    )
    (property "Value" "C_100n_0402" (at 356.235 139.7 0)
      (effects (font (size 1.27 1.27) (thickness 0.15)) (justify left bottom) hide)
    )
    (property "Footprint" "antmicro-footprints:C_0402_1005Metric" (at 353.695 139.7 0)
      (effects (font (size 1.27 1.27) (thickness 0.15)) (justify left bottom) hide)
    )
    (property "Datasheet" "https://search.murata.co.jp/Ceramy/image/img/A01X/G101/ENG/GRM155R61H104KE14-01.pdf" (at 351.155 139.7 0)
      (effects (font (size 1.27 1.27) (thickness 0.15)) (justify left bottom) hide)
    )
    (property "Manufacturer" "Murata" (at 346.075 139.7 0)
      (effects (font (size 1.27 1.27) (thickness 0.15)) (justify left bottom) hide)
    )
    (property "MPN" "GRM155R61H104KE14D" (at 348.615 139.7 0)
      (effects (font (size 1.27 1.27) (thickness 0.15)) (justify left bottom) hide)
    )
    (property "Val" "100n" (at 366.395 123.825 90)
      (effects (font (size 1.27 1.27) (thickness 0.15)) (justify left))
    )
    (property "License" "Apache-2.0" (at 343.535 139.7 0)
      (effects (font (size 1.27 1.27) (thickness 0.15)) (justify left bottom) hide)
    )
    (property "Author" "Antmicro" (at 340.995 139.7 0)
      (effects (font (size 1.27 1.27) (thickness 0.15)) (justify left bottom) hide)
    )
    (property "Voltage" "50V" (at 338.455 139.7 0)
      (effects (font (size 1.27 1.27)) (justify left bottom) hide)
    )
    (property "Dielectric" "X5R" (at 335.915 139.7 0)
      (effects (font (size 1.27 1.27)) (justify left bottom) hide)
    )
    (pin "1")
    (pin "2")
    (instances
      (project "data-center-rdimm-ddr4-tester"
        (path ""
          (reference "C181") (unit 1)
        )
      )
    )
  )

  (symbol (lib_id "antmicroCapacitors0402:C_100n_0402") (at 334.645 119.38 270) (unit 1)
    (in_bom yes) (on_board yes) (dnp no)
    (property "Reference" "C171" (at 334.645 120.015 90)
      (effects (font (size 1.524 1.524)) (justify left))
    )
    (property "Value" "C_100n_0402" (at 324.485 139.7 0)
      (effects (font (size 1.27 1.27) (thickness 0.15)) (justify left bottom) hide)
    )
    (property "Footprint" "antmicro-footprints:C_0402_1005Metric" (at 321.945 139.7 0)
      (effects (font (size 1.27 1.27) (thickness 0.15)) (justify left bottom) hide)
    )
    (property "Datasheet" "https://search.murata.co.jp/Ceramy/image/img/A01X/G101/ENG/GRM155R61H104KE14-01.pdf" (at 319.405 139.7 0)
      (effects (font (size 1.27 1.27) (thickness 0.15)) (justify left bottom) hide)
    )
    (property "Manufacturer" "Murata" (at 314.325 139.7 0)
      (effects (font (size 1.27 1.27) (thickness 0.15)) (justify left bottom) hide)
    )
    (property "MPN" "GRM155R61H104KE14D" (at 316.865 139.7 0)
      (effects (font (size 1.27 1.27) (thickness 0.15)) (justify left bottom) hide)
    )
    (property "Val" "100n" (at 334.645 123.825 90)
      (effects (font (size 1.27 1.27) (thickness 0.15)) (justify left))
    )
    (property "License" "Apache-2.0" (at 311.785 139.7 0)
      (effects (font (size 1.27 1.27) (thickness 0.15)) (justify left bottom) hide)
    )
    (property "Author" "Antmicro" (at 309.245 139.7 0)
      (effects (font (size 1.27 1.27) (thickness 0.15)) (justify left bottom) hide)
    )
    (property "Voltage" "50V" (at 306.705 139.7 0)
      (effects (font (size 1.27 1.27)) (justify left bottom) hide)
    )
    (property "Dielectric" "X5R" (at 304.165 139.7 0)
      (effects (font (size 1.27 1.27)) (justify left bottom) hide)
    )
    (pin "1")
    (pin "2")
    (instances
      (project "data-center-rdimm-ddr4-tester"
        (path ""
          (reference "C171") (unit 1)
        )
      )
    )
  )

  (symbol (lib_id "antmicroCapacitors0402:C_100n_0402") (at 340.995 119.38 270) (unit 1)
    (in_bom yes) (on_board yes) (dnp no)
    (property "Reference" "C173" (at 340.995 120.015 90)
      (effects (font (size 1.524 1.524)) (justify left))
    )
    (property "Value" "C_100n_0402" (at 330.835 139.7 0)
      (effects (font (size 1.27 1.27) (thickness 0.15)) (justify left bottom) hide)
    )
    (property "Footprint" "antmicro-footprints:C_0402_1005Metric" (at 328.295 139.7 0)
      (effects (font (size 1.27 1.27) (thickness 0.15)) (justify left bottom) hide)
    )
    (property "Datasheet" "https://search.murata.co.jp/Ceramy/image/img/A01X/G101/ENG/GRM155R61H104KE14-01.pdf" (at 325.755 139.7 0)
      (effects (font (size 1.27 1.27) (thickness 0.15)) (justify left bottom) hide)
    )
    (property "Manufacturer" "Murata" (at 320.675 139.7 0)
      (effects (font (size 1.27 1.27) (thickness 0.15)) (justify left bottom) hide)
    )
    (property "MPN" "GRM155R61H104KE14D" (at 323.215 139.7 0)
      (effects (font (size 1.27 1.27) (thickness 0.15)) (justify left bottom) hide)
    )
    (property "Val" "100n" (at 340.995 123.825 90)
      (effects (font (size 1.27 1.27) (thickness 0.15)) (justify left))
    )
    (property "License" "Apache-2.0" (at 318.135 139.7 0)
      (effects (font (size 1.27 1.27) (thickness 0.15)) (justify left bottom) hide)
    )
    (property "Author" "Antmicro" (at 315.595 139.7 0)
      (effects (font (size 1.27 1.27) (thickness 0.15)) (justify left bottom) hide)
    )
    (property "Voltage" "50V" (at 313.055 139.7 0)
      (effects (font (size 1.27 1.27)) (justify left bottom) hide)
    )
    (property "Dielectric" "X5R" (at 310.515 139.7 0)
      (effects (font (size 1.27 1.27)) (justify left bottom) hide)
    )
    (pin "1")
    (pin "2")
    (instances
      (project "data-center-rdimm-ddr4-tester"
        (path ""
          (reference "C173") (unit 1)
        )
      )
    )
  )

  (symbol (lib_id "antmicroCapacitors0402:C_100n_0402") (at 347.345 119.38 270) (unit 1)
    (in_bom yes) (on_board yes) (dnp no)
    (property "Reference" "C176" (at 347.345 120.015 90)
      (effects (font (size 1.524 1.524)) (justify left))
    )
    (property "Value" "C_100n_0402" (at 337.185 139.7 0)
      (effects (font (size 1.27 1.27) (thickness 0.15)) (justify left bottom) hide)
    )
    (property "Footprint" "antmicro-footprints:C_0402_1005Metric" (at 334.645 139.7 0)
      (effects (font (size 1.27 1.27) (thickness 0.15)) (justify left bottom) hide)
    )
    (property "Datasheet" "https://search.murata.co.jp/Ceramy/image/img/A01X/G101/ENG/GRM155R61H104KE14-01.pdf" (at 332.105 139.7 0)
      (effects (font (size 1.27 1.27) (thickness 0.15)) (justify left bottom) hide)
    )
    (property "Manufacturer" "Murata" (at 327.025 139.7 0)
      (effects (font (size 1.27 1.27) (thickness 0.15)) (justify left bottom) hide)
    )
    (property "MPN" "GRM155R61H104KE14D" (at 329.565 139.7 0)
      (effects (font (size 1.27 1.27) (thickness 0.15)) (justify left bottom) hide)
    )
    (property "Val" "100n" (at 347.345 123.825 90)
      (effects (font (size 1.27 1.27) (thickness 0.15)) (justify left))
    )
    (property "License" "Apache-2.0" (at 324.485 139.7 0)
      (effects (font (size 1.27 1.27) (thickness 0.15)) (justify left bottom) hide)
    )
    (property "Author" "Antmicro" (at 321.945 139.7 0)
      (effects (font (size 1.27 1.27) (thickness 0.15)) (justify left bottom) hide)
    )
    (property "Voltage" "50V" (at 319.405 139.7 0)
      (effects (font (size 1.27 1.27)) (justify left bottom) hide)
    )
    (property "Dielectric" "X5R" (at 316.865 139.7 0)
      (effects (font (size 1.27 1.27)) (justify left bottom) hide)
    )
    (pin "1")
    (pin "2")
    (instances
      (project "data-center-rdimm-ddr4-tester"
        (path ""
          (reference "C176") (unit 1)
        )
      )
    )
  )

  (symbol (lib_id "antmicroCapacitors0402:C_100n_0402") (at 353.695 119.38 270) (unit 1)
    (in_bom yes) (on_board yes) (dnp no)
    (property "Reference" "C177" (at 353.695 120.015 90)
      (effects (font (size 1.524 1.524)) (justify left))
    )
    (property "Value" "C_100n_0402" (at 343.535 139.7 0)
      (effects (font (size 1.27 1.27) (thickness 0.15)) (justify left bottom) hide)
    )
    (property "Footprint" "antmicro-footprints:C_0402_1005Metric" (at 340.995 139.7 0)
      (effects (font (size 1.27 1.27) (thickness 0.15)) (justify left bottom) hide)
    )
    (property "Datasheet" "https://search.murata.co.jp/Ceramy/image/img/A01X/G101/ENG/GRM155R61H104KE14-01.pdf" (at 338.455 139.7 0)
      (effects (font (size 1.27 1.27) (thickness 0.15)) (justify left bottom) hide)
    )
    (property "Manufacturer" "Murata" (at 333.375 139.7 0)
      (effects (font (size 1.27 1.27) (thickness 0.15)) (justify left bottom) hide)
    )
    (property "MPN" "GRM155R61H104KE14D" (at 335.915 139.7 0)
      (effects (font (size 1.27 1.27) (thickness 0.15)) (justify left bottom) hide)
    )
    (property "Val" "100n" (at 353.695 123.825 90)
      (effects (font (size 1.27 1.27) (thickness 0.15)) (justify left))
    )
    (property "License" "Apache-2.0" (at 330.835 139.7 0)
      (effects (font (size 1.27 1.27) (thickness 0.15)) (justify left bottom) hide)
    )
    (property "Author" "Antmicro" (at 328.295 139.7 0)
      (effects (font (size 1.27 1.27) (thickness 0.15)) (justify left bottom) hide)
    )
    (property "Voltage" "50V" (at 325.755 139.7 0)
      (effects (font (size 1.27 1.27)) (justify left bottom) hide)
    )
    (property "Dielectric" "X5R" (at 323.215 139.7 0)
      (effects (font (size 1.27 1.27)) (justify left bottom) hide)
    )
    (pin "1")
    (pin "2")
    (instances
      (project "data-center-rdimm-ddr4-tester"
        (path ""
          (reference "C177") (unit 1)
        )
      )
    )
  )

  (symbol (lib_id "antmicropower:GND") (at 334.645 124.46 0) (unit 1)
    (in_bom yes) (on_board yes) (dnp no) (fields_autoplaced)
    (property "Reference" "#PWR0281" (at 334.645 130.81 0)
      (effects (font (size 1.27 1.27)) hide)
    )
    (property "Value" "GND" (at 334.645 129.54 0)
      (effects (font (size 1.27 1.27)))
    )
    (property "Footprint" "" (at 334.645 124.46 0)
      (effects (font (size 1.27 1.27)) hide)
    )
    (property "Datasheet" "" (at 334.645 124.46 0)
      (effects (font (size 1.27 1.27)) hide)
    )
    (property "Author" "Antmicro" (at 343.535 132.08 0)
      (effects (font (size 1.27 1.27) (thickness 0.15)) (justify left bottom) hide)
    )
    (property "License" "Apache-2.0" (at 343.535 134.62 0)
      (effects (font (size 1.27 1.27) (thickness 0.15)) (justify left bottom) hide)
    )
    (pin "1")
    (instances
      (project "data-center-rdimm-ddr4-tester"
        (path ""
          (reference "#PWR0281") (unit 1)
        )
      )
    )
  )

  (symbol (lib_id "antmicropower:GND") (at 340.995 124.46 0) (unit 1)
    (in_bom yes) (on_board yes) (dnp no) (fields_autoplaced)
    (property "Reference" "#PWR0282" (at 340.995 130.81 0)
      (effects (font (size 1.27 1.27)) hide)
    )
    (property "Value" "GND" (at 340.995 129.54 0)
      (effects (font (size 1.27 1.27)))
    )
    (property "Footprint" "" (at 340.995 124.46 0)
      (effects (font (size 1.27 1.27)) hide)
    )
    (property "Datasheet" "" (at 340.995 124.46 0)
      (effects (font (size 1.27 1.27)) hide)
    )
    (property "Author" "Antmicro" (at 349.885 132.08 0)
      (effects (font (size 1.27 1.27) (thickness 0.15)) (justify left bottom) hide)
    )
    (property "License" "Apache-2.0" (at 349.885 134.62 0)
      (effects (font (size 1.27 1.27) (thickness 0.15)) (justify left bottom) hide)
    )
    (pin "1")
    (instances
      (project "data-center-rdimm-ddr4-tester"
        (path ""
          (reference "#PWR0282") (unit 1)
        )
      )
    )
  )

  (symbol (lib_id "antmicropower:GND") (at 347.345 124.46 0) (unit 1)
    (in_bom yes) (on_board yes) (dnp no) (fields_autoplaced)
    (property "Reference" "#PWR0283" (at 347.345 130.81 0)
      (effects (font (size 1.27 1.27)) hide)
    )
    (property "Value" "GND" (at 347.345 129.54 0)
      (effects (font (size 1.27 1.27)))
    )
    (property "Footprint" "" (at 347.345 124.46 0)
      (effects (font (size 1.27 1.27)) hide)
    )
    (property "Datasheet" "" (at 347.345 124.46 0)
      (effects (font (size 1.27 1.27)) hide)
    )
    (property "Author" "Antmicro" (at 356.235 132.08 0)
      (effects (font (size 1.27 1.27) (thickness 0.15)) (justify left bottom) hide)
    )
    (property "License" "Apache-2.0" (at 356.235 134.62 0)
      (effects (font (size 1.27 1.27) (thickness 0.15)) (justify left bottom) hide)
    )
    (pin "1")
    (instances
      (project "data-center-rdimm-ddr4-tester"
        (path ""
          (reference "#PWR0283") (unit 1)
        )
      )
    )
  )

  (symbol (lib_id "antmicropower:GND") (at 353.695 124.46 0) (unit 1)
    (in_bom yes) (on_board yes) (dnp no) (fields_autoplaced)
    (property "Reference" "#PWR0284" (at 353.695 130.81 0)
      (effects (font (size 1.27 1.27)) hide)
    )
    (property "Value" "GND" (at 353.695 129.54 0)
      (effects (font (size 1.27 1.27)))
    )
    (property "Footprint" "" (at 353.695 124.46 0)
      (effects (font (size 1.27 1.27)) hide)
    )
    (property "Datasheet" "" (at 353.695 124.46 0)
      (effects (font (size 1.27 1.27)) hide)
    )
    (property "Author" "Antmicro" (at 362.585 132.08 0)
      (effects (font (size 1.27 1.27) (thickness 0.15)) (justify left bottom) hide)
    )
    (property "License" "Apache-2.0" (at 362.585 134.62 0)
      (effects (font (size 1.27 1.27) (thickness 0.15)) (justify left bottom) hide)
    )
    (pin "1")
    (instances
      (project "data-center-rdimm-ddr4-tester"
        (path ""
          (reference "#PWR0284") (unit 1)
        )
      )
    )
  )

  (symbol (lib_id "antmicropower:GND") (at 360.045 124.46 0) (unit 1)
    (in_bom yes) (on_board yes) (dnp no) (fields_autoplaced)
    (property "Reference" "#PWR0285" (at 360.045 130.81 0)
      (effects (font (size 1.27 1.27)) hide)
    )
    (property "Value" "GND" (at 360.045 129.54 0)
      (effects (font (size 1.27 1.27)))
    )
    (property "Footprint" "" (at 360.045 124.46 0)
      (effects (font (size 1.27 1.27)) hide)
    )
    (property "Datasheet" "" (at 360.045 124.46 0)
      (effects (font (size 1.27 1.27)) hide)
    )
    (property "Author" "Antmicro" (at 368.935 132.08 0)
      (effects (font (size 1.27 1.27) (thickness 0.15)) (justify left bottom) hide)
    )
    (property "License" "Apache-2.0" (at 368.935 134.62 0)
      (effects (font (size 1.27 1.27) (thickness 0.15)) (justify left bottom) hide)
    )
    (pin "1")
    (instances
      (project "data-center-rdimm-ddr4-tester"
        (path ""
          (reference "#PWR0285") (unit 1)
        )
      )
    )
  )

  (symbol (lib_id "antmicropower:GND") (at 366.395 124.46 0) (unit 1)
    (in_bom yes) (on_board yes) (dnp no) (fields_autoplaced)
    (property "Reference" "#PWR0286" (at 366.395 130.81 0)
      (effects (font (size 1.27 1.27)) hide)
    )
    (property "Value" "GND" (at 366.395 129.54 0)
      (effects (font (size 1.27 1.27)))
    )
    (property "Footprint" "" (at 366.395 124.46 0)
      (effects (font (size 1.27 1.27)) hide)
    )
    (property "Datasheet" "" (at 366.395 124.46 0)
      (effects (font (size 1.27 1.27)) hide)
    )
    (property "Author" "Antmicro" (at 375.285 132.08 0)
      (effects (font (size 1.27 1.27) (thickness 0.15)) (justify left bottom) hide)
    )
    (property "License" "Apache-2.0" (at 375.285 134.62 0)
      (effects (font (size 1.27 1.27) (thickness 0.15)) (justify left bottom) hide)
    )
    (pin "1")
    (instances
      (project "data-center-rdimm-ddr4-tester"
        (path ""
          (reference "#PWR0286") (unit 1)
        )
      )
    )
  )

  (symbol (lib_id "antmicroCapacitors0402:C_100n_0402") (at 360.045 138.43 270) (unit 1)
    (in_bom yes) (on_board yes) (dnp no)
    (property "Reference" "C203" (at 360.045 139.065 90)
      (effects (font (size 1.524 1.524)) (justify left))
    )
    (property "Value" "C_100n_0402" (at 349.885 158.75 0)
      (effects (font (size 1.27 1.27) (thickness 0.15)) (justify left bottom) hide)
    )
    (property "Footprint" "antmicro-footprints:C_0402_1005Metric" (at 347.345 158.75 0)
      (effects (font (size 1.27 1.27) (thickness 0.15)) (justify left bottom) hide)
    )
    (property "Datasheet" "https://search.murata.co.jp/Ceramy/image/img/A01X/G101/ENG/GRM155R61H104KE14-01.pdf" (at 344.805 158.75 0)
      (effects (font (size 1.27 1.27) (thickness 0.15)) (justify left bottom) hide)
    )
    (property "Manufacturer" "Murata" (at 339.725 158.75 0)
      (effects (font (size 1.27 1.27) (thickness 0.15)) (justify left bottom) hide)
    )
    (property "MPN" "GRM155R61H104KE14D" (at 342.265 158.75 0)
      (effects (font (size 1.27 1.27) (thickness 0.15)) (justify left bottom) hide)
    )
    (property "Val" "100n" (at 360.045 142.875 90)
      (effects (font (size 1.27 1.27) (thickness 0.15)) (justify left))
    )
    (property "License" "Apache-2.0" (at 337.185 158.75 0)
      (effects (font (size 1.27 1.27) (thickness 0.15)) (justify left bottom) hide)
    )
    (property "Author" "Antmicro" (at 334.645 158.75 0)
      (effects (font (size 1.27 1.27) (thickness 0.15)) (justify left bottom) hide)
    )
    (property "Voltage" "50V" (at 332.105 158.75 0)
      (effects (font (size 1.27 1.27)) (justify left bottom) hide)
    )
    (property "Dielectric" "X5R" (at 329.565 158.75 0)
      (effects (font (size 1.27 1.27)) (justify left bottom) hide)
    )
    (pin "1")
    (pin "2")
    (instances
      (project "data-center-rdimm-ddr4-tester"
        (path ""
          (reference "C203") (unit 1)
        )
      )
    )
  )

  (symbol (lib_id "antmicroCapacitors0402:C_100n_0402") (at 334.645 138.43 270) (unit 1)
    (in_bom yes) (on_board yes) (dnp no)
    (property "Reference" "C199" (at 334.645 139.065 90)
      (effects (font (size 1.524 1.524)) (justify left))
    )
    (property "Value" "C_100n_0402" (at 324.485 158.75 0)
      (effects (font (size 1.27 1.27) (thickness 0.15)) (justify left bottom) hide)
    )
    (property "Footprint" "antmicro-footprints:C_0402_1005Metric" (at 321.945 158.75 0)
      (effects (font (size 1.27 1.27) (thickness 0.15)) (justify left bottom) hide)
    )
    (property "Datasheet" "https://search.murata.co.jp/Ceramy/image/img/A01X/G101/ENG/GRM155R61H104KE14-01.pdf" (at 319.405 158.75 0)
      (effects (font (size 1.27 1.27) (thickness 0.15)) (justify left bottom) hide)
    )
    (property "Manufacturer" "Murata" (at 314.325 158.75 0)
      (effects (font (size 1.27 1.27) (thickness 0.15)) (justify left bottom) hide)
    )
    (property "MPN" "GRM155R61H104KE14D" (at 316.865 158.75 0)
      (effects (font (size 1.27 1.27) (thickness 0.15)) (justify left bottom) hide)
    )
    (property "Val" "100n" (at 334.645 142.875 90)
      (effects (font (size 1.27 1.27) (thickness 0.15)) (justify left))
    )
    (property "License" "Apache-2.0" (at 311.785 158.75 0)
      (effects (font (size 1.27 1.27) (thickness 0.15)) (justify left bottom) hide)
    )
    (property "Author" "Antmicro" (at 309.245 158.75 0)
      (effects (font (size 1.27 1.27) (thickness 0.15)) (justify left bottom) hide)
    )
    (property "Voltage" "50V" (at 306.705 158.75 0)
      (effects (font (size 1.27 1.27)) (justify left bottom) hide)
    )
    (property "Dielectric" "X5R" (at 304.165 158.75 0)
      (effects (font (size 1.27 1.27)) (justify left bottom) hide)
    )
    (pin "1")
    (pin "2")
    (instances
      (project "data-center-rdimm-ddr4-tester"
        (path ""
          (reference "C199") (unit 1)
        )
      )
    )
  )

  (symbol (lib_id "antmicroCapacitors0402:C_100n_0402") (at 340.995 138.43 270) (unit 1)
    (in_bom yes) (on_board yes) (dnp no)
    (property "Reference" "C200" (at 340.995 139.065 90)
      (effects (font (size 1.524 1.524)) (justify left))
    )
    (property "Value" "C_100n_0402" (at 330.835 158.75 0)
      (effects (font (size 1.27 1.27) (thickness 0.15)) (justify left bottom) hide)
    )
    (property "Footprint" "antmicro-footprints:C_0402_1005Metric" (at 328.295 158.75 0)
      (effects (font (size 1.27 1.27) (thickness 0.15)) (justify left bottom) hide)
    )
    (property "Datasheet" "https://search.murata.co.jp/Ceramy/image/img/A01X/G101/ENG/GRM155R61H104KE14-01.pdf" (at 325.755 158.75 0)
      (effects (font (size 1.27 1.27) (thickness 0.15)) (justify left bottom) hide)
    )
    (property "Manufacturer" "Murata" (at 320.675 158.75 0)
      (effects (font (size 1.27 1.27) (thickness 0.15)) (justify left bottom) hide)
    )
    (property "MPN" "GRM155R61H104KE14D" (at 323.215 158.75 0)
      (effects (font (size 1.27 1.27) (thickness 0.15)) (justify left bottom) hide)
    )
    (property "Val" "100n" (at 340.995 142.875 90)
      (effects (font (size 1.27 1.27) (thickness 0.15)) (justify left))
    )
    (property "License" "Apache-2.0" (at 318.135 158.75 0)
      (effects (font (size 1.27 1.27) (thickness 0.15)) (justify left bottom) hide)
    )
    (property "Author" "Antmicro" (at 315.595 158.75 0)
      (effects (font (size 1.27 1.27) (thickness 0.15)) (justify left bottom) hide)
    )
    (property "Voltage" "50V" (at 313.055 158.75 0)
      (effects (font (size 1.27 1.27)) (justify left bottom) hide)
    )
    (property "Dielectric" "X5R" (at 310.515 158.75 0)
      (effects (font (size 1.27 1.27)) (justify left bottom) hide)
    )
    (pin "1")
    (pin "2")
    (instances
      (project "data-center-rdimm-ddr4-tester"
        (path ""
          (reference "C200") (unit 1)
        )
      )
    )
  )

  (symbol (lib_id "antmicroCapacitors0402:C_100n_0402") (at 347.345 138.43 270) (unit 1)
    (in_bom yes) (on_board yes) (dnp no)
    (property "Reference" "C201" (at 347.345 139.065 90)
      (effects (font (size 1.524 1.524)) (justify left))
    )
    (property "Value" "C_100n_0402" (at 337.185 158.75 0)
      (effects (font (size 1.27 1.27) (thickness 0.15)) (justify left bottom) hide)
    )
    (property "Footprint" "antmicro-footprints:C_0402_1005Metric" (at 334.645 158.75 0)
      (effects (font (size 1.27 1.27) (thickness 0.15)) (justify left bottom) hide)
    )
    (property "Datasheet" "https://search.murata.co.jp/Ceramy/image/img/A01X/G101/ENG/GRM155R61H104KE14-01.pdf" (at 332.105 158.75 0)
      (effects (font (size 1.27 1.27) (thickness 0.15)) (justify left bottom) hide)
    )
    (property "Manufacturer" "Murata" (at 327.025 158.75 0)
      (effects (font (size 1.27 1.27) (thickness 0.15)) (justify left bottom) hide)
    )
    (property "MPN" "GRM155R61H104KE14D" (at 329.565 158.75 0)
      (effects (font (size 1.27 1.27) (thickness 0.15)) (justify left bottom) hide)
    )
    (property "Val" "100n" (at 347.345 142.875 90)
      (effects (font (size 1.27 1.27) (thickness 0.15)) (justify left))
    )
    (property "License" "Apache-2.0" (at 324.485 158.75 0)
      (effects (font (size 1.27 1.27) (thickness 0.15)) (justify left bottom) hide)
    )
    (property "Author" "Antmicro" (at 321.945 158.75 0)
      (effects (font (size 1.27 1.27) (thickness 0.15)) (justify left bottom) hide)
    )
    (property "Voltage" "50V" (at 319.405 158.75 0)
      (effects (font (size 1.27 1.27)) (justify left bottom) hide)
    )
    (property "Dielectric" "X5R" (at 316.865 158.75 0)
      (effects (font (size 1.27 1.27)) (justify left bottom) hide)
    )
    (pin "1")
    (pin "2")
    (instances
      (project "data-center-rdimm-ddr4-tester"
        (path ""
          (reference "C201") (unit 1)
        )
      )
    )
  )

  (symbol (lib_id "antmicroCapacitors0402:C_100n_0402") (at 353.695 138.43 270) (unit 1)
    (in_bom yes) (on_board yes) (dnp no)
    (property "Reference" "C202" (at 360.045 139.065 90)
      (effects (font (size 1.524 1.524)) (justify right))
    )
    (property "Value" "C_100n_0402" (at 343.535 158.75 0)
      (effects (font (size 1.27 1.27) (thickness 0.15)) (justify left bottom) hide)
    )
    (property "Footprint" "antmicro-footprints:C_0402_1005Metric" (at 340.995 158.75 0)
      (effects (font (size 1.27 1.27) (thickness 0.15)) (justify left bottom) hide)
    )
    (property "Datasheet" "https://search.murata.co.jp/Ceramy/image/img/A01X/G101/ENG/GRM155R61H104KE14-01.pdf" (at 338.455 158.75 0)
      (effects (font (size 1.27 1.27) (thickness 0.15)) (justify left bottom) hide)
    )
    (property "Manufacturer" "Murata" (at 333.375 158.75 0)
      (effects (font (size 1.27 1.27) (thickness 0.15)) (justify left bottom) hide)
    )
    (property "MPN" "GRM155R61H104KE14D" (at 335.915 158.75 0)
      (effects (font (size 1.27 1.27) (thickness 0.15)) (justify left bottom) hide)
    )
    (property "Val" "100n" (at 358.775 142.875 90)
      (effects (font (size 1.27 1.27) (thickness 0.15)) (justify right))
    )
    (property "License" "Apache-2.0" (at 330.835 158.75 0)
      (effects (font (size 1.27 1.27) (thickness 0.15)) (justify left bottom) hide)
    )
    (property "Author" "Antmicro" (at 328.295 158.75 0)
      (effects (font (size 1.27 1.27) (thickness 0.15)) (justify left bottom) hide)
    )
    (property "Voltage" "50V" (at 325.755 158.75 0)
      (effects (font (size 1.27 1.27)) (justify left bottom) hide)
    )
    (property "Dielectric" "X5R" (at 323.215 158.75 0)
      (effects (font (size 1.27 1.27)) (justify left bottom) hide)
    )
    (pin "1")
    (pin "2")
    (instances
      (project "data-center-rdimm-ddr4-tester"
        (path ""
          (reference "C202") (unit 1)
        )
      )
    )
  )

  (symbol (lib_id "antmicropower:GND") (at 334.645 143.51 0) (unit 1)
    (in_bom yes) (on_board yes) (dnp no) (fields_autoplaced)
    (property "Reference" "#PWR0287" (at 334.645 149.86 0)
      (effects (font (size 1.27 1.27)) hide)
    )
    (property "Value" "GND" (at 334.645 148.59 0)
      (effects (font (size 1.27 1.27)))
    )
    (property "Footprint" "" (at 334.645 143.51 0)
      (effects (font (size 1.27 1.27)) hide)
    )
    (property "Datasheet" "" (at 334.645 143.51 0)
      (effects (font (size 1.27 1.27)) hide)
    )
    (property "Author" "Antmicro" (at 343.535 151.13 0)
      (effects (font (size 1.27 1.27) (thickness 0.15)) (justify left bottom) hide)
    )
    (property "License" "Apache-2.0" (at 343.535 153.67 0)
      (effects (font (size 1.27 1.27) (thickness 0.15)) (justify left bottom) hide)
    )
    (pin "1")
    (instances
      (project "data-center-rdimm-ddr4-tester"
        (path ""
          (reference "#PWR0287") (unit 1)
        )
      )
    )
  )

  (symbol (lib_id "antmicropower:GND") (at 340.995 143.51 0) (unit 1)
    (in_bom yes) (on_board yes) (dnp no) (fields_autoplaced)
    (property "Reference" "#PWR0288" (at 340.995 149.86 0)
      (effects (font (size 1.27 1.27)) hide)
    )
    (property "Value" "GND" (at 340.995 148.59 0)
      (effects (font (size 1.27 1.27)))
    )
    (property "Footprint" "" (at 340.995 143.51 0)
      (effects (font (size 1.27 1.27)) hide)
    )
    (property "Datasheet" "" (at 340.995 143.51 0)
      (effects (font (size 1.27 1.27)) hide)
    )
    (property "Author" "Antmicro" (at 349.885 151.13 0)
      (effects (font (size 1.27 1.27) (thickness 0.15)) (justify left bottom) hide)
    )
    (property "License" "Apache-2.0" (at 349.885 153.67 0)
      (effects (font (size 1.27 1.27) (thickness 0.15)) (justify left bottom) hide)
    )
    (pin "1")
    (instances
      (project "data-center-rdimm-ddr4-tester"
        (path ""
          (reference "#PWR0288") (unit 1)
        )
      )
    )
  )

  (symbol (lib_id "antmicropower:GND") (at 347.345 143.51 0) (unit 1)
    (in_bom yes) (on_board yes) (dnp no) (fields_autoplaced)
    (property "Reference" "#PWR0289" (at 347.345 149.86 0)
      (effects (font (size 1.27 1.27)) hide)
    )
    (property "Value" "GND" (at 347.345 148.59 0)
      (effects (font (size 1.27 1.27)))
    )
    (property "Footprint" "" (at 347.345 143.51 0)
      (effects (font (size 1.27 1.27)) hide)
    )
    (property "Datasheet" "" (at 347.345 143.51 0)
      (effects (font (size 1.27 1.27)) hide)
    )
    (property "Author" "Antmicro" (at 356.235 151.13 0)
      (effects (font (size 1.27 1.27) (thickness 0.15)) (justify left bottom) hide)
    )
    (property "License" "Apache-2.0" (at 356.235 153.67 0)
      (effects (font (size 1.27 1.27) (thickness 0.15)) (justify left bottom) hide)
    )
    (pin "1")
    (instances
      (project "data-center-rdimm-ddr4-tester"
        (path ""
          (reference "#PWR0289") (unit 1)
        )
      )
    )
  )

  (symbol (lib_id "antmicropower:GND") (at 353.695 143.51 0) (unit 1)
    (in_bom yes) (on_board yes) (dnp no) (fields_autoplaced)
    (property "Reference" "#PWR0290" (at 353.695 149.86 0)
      (effects (font (size 1.27 1.27)) hide)
    )
    (property "Value" "GND" (at 353.695 148.59 0)
      (effects (font (size 1.27 1.27)))
    )
    (property "Footprint" "" (at 353.695 143.51 0)
      (effects (font (size 1.27 1.27)) hide)
    )
    (property "Datasheet" "" (at 353.695 143.51 0)
      (effects (font (size 1.27 1.27)) hide)
    )
    (property "Author" "Antmicro" (at 362.585 151.13 0)
      (effects (font (size 1.27 1.27) (thickness 0.15)) (justify left bottom) hide)
    )
    (property "License" "Apache-2.0" (at 362.585 153.67 0)
      (effects (font (size 1.27 1.27) (thickness 0.15)) (justify left bottom) hide)
    )
    (pin "1")
    (instances
      (project "data-center-rdimm-ddr4-tester"
        (path ""
          (reference "#PWR0290") (unit 1)
        )
      )
    )
  )

  (symbol (lib_id "antmicropower:GND") (at 360.045 143.51 0) (unit 1)
    (in_bom yes) (on_board yes) (dnp no) (fields_autoplaced)
    (property "Reference" "#PWR0291" (at 360.045 149.86 0)
      (effects (font (size 1.27 1.27)) hide)
    )
    (property "Value" "GND" (at 360.045 148.59 0)
      (effects (font (size 1.27 1.27)))
    )
    (property "Footprint" "" (at 360.045 143.51 0)
      (effects (font (size 1.27 1.27)) hide)
    )
    (property "Datasheet" "" (at 360.045 143.51 0)
      (effects (font (size 1.27 1.27)) hide)
    )
    (property "Author" "Antmicro" (at 368.935 151.13 0)
      (effects (font (size 1.27 1.27) (thickness 0.15)) (justify left bottom) hide)
    )
    (property "License" "Apache-2.0" (at 368.935 153.67 0)
      (effects (font (size 1.27 1.27) (thickness 0.15)) (justify left bottom) hide)
    )
    (pin "1")
    (instances
      (project "data-center-rdimm-ddr4-tester"
        (path ""
          (reference "#PWR0291") (unit 1)
        )
      )
    )
  )

  (symbol (lib_id "antmicroCapacitors0402:C_100n_0402") (at 334.645 158.115 270) (unit 1)
    (in_bom yes) (on_board yes) (dnp no)
    (property "Reference" "C204" (at 334.645 158.75 90)
      (effects (font (size 1.524 1.524)) (justify left))
    )
    (property "Value" "C_100n_0402" (at 324.485 178.435 0)
      (effects (font (size 1.27 1.27) (thickness 0.15)) (justify left bottom) hide)
    )
    (property "Footprint" "antmicro-footprints:C_0402_1005Metric" (at 321.945 178.435 0)
      (effects (font (size 1.27 1.27) (thickness 0.15)) (justify left bottom) hide)
    )
    (property "Datasheet" "https://search.murata.co.jp/Ceramy/image/img/A01X/G101/ENG/GRM155R61H104KE14-01.pdf" (at 319.405 178.435 0)
      (effects (font (size 1.27 1.27) (thickness 0.15)) (justify left bottom) hide)
    )
    (property "Manufacturer" "Murata" (at 314.325 178.435 0)
      (effects (font (size 1.27 1.27) (thickness 0.15)) (justify left bottom) hide)
    )
    (property "MPN" "GRM155R61H104KE14D" (at 316.865 178.435 0)
      (effects (font (size 1.27 1.27) (thickness 0.15)) (justify left bottom) hide)
    )
    (property "Val" "100n" (at 334.645 162.56 90)
      (effects (font (size 1.27 1.27) (thickness 0.15)) (justify left))
    )
    (property "License" "Apache-2.0" (at 311.785 178.435 0)
      (effects (font (size 1.27 1.27) (thickness 0.15)) (justify left bottom) hide)
    )
    (property "Author" "Antmicro" (at 309.245 178.435 0)
      (effects (font (size 1.27 1.27) (thickness 0.15)) (justify left bottom) hide)
    )
    (property "Voltage" "50V" (at 306.705 178.435 0)
      (effects (font (size 1.27 1.27)) (justify left bottom) hide)
    )
    (property "Dielectric" "X5R" (at 304.165 178.435 0)
      (effects (font (size 1.27 1.27)) (justify left bottom) hide)
    )
    (pin "1")
    (pin "2")
    (instances
      (project "data-center-rdimm-ddr4-tester"
        (path ""
          (reference "C204") (unit 1)
        )
      )
    )
  )

  (symbol (lib_id "antmicroCapacitors0402:C_100n_0402") (at 340.995 158.115 270) (unit 1)
    (in_bom yes) (on_board yes) (dnp no)
    (property "Reference" "C205" (at 340.995 158.75 90)
      (effects (font (size 1.524 1.524)) (justify left))
    )
    (property "Value" "C_100n_0402" (at 330.835 178.435 0)
      (effects (font (size 1.27 1.27) (thickness 0.15)) (justify left bottom) hide)
    )
    (property "Footprint" "antmicro-footprints:C_0402_1005Metric" (at 328.295 178.435 0)
      (effects (font (size 1.27 1.27) (thickness 0.15)) (justify left bottom) hide)
    )
    (property "Datasheet" "https://search.murata.co.jp/Ceramy/image/img/A01X/G101/ENG/GRM155R61H104KE14-01.pdf" (at 325.755 178.435 0)
      (effects (font (size 1.27 1.27) (thickness 0.15)) (justify left bottom) hide)
    )
    (property "Manufacturer" "Murata" (at 320.675 178.435 0)
      (effects (font (size 1.27 1.27) (thickness 0.15)) (justify left bottom) hide)
    )
    (property "MPN" "GRM155R61H104KE14D" (at 323.215 178.435 0)
      (effects (font (size 1.27 1.27) (thickness 0.15)) (justify left bottom) hide)
    )
    (property "Val" "100n" (at 340.995 162.56 90)
      (effects (font (size 1.27 1.27) (thickness 0.15)) (justify left))
    )
    (property "License" "Apache-2.0" (at 318.135 178.435 0)
      (effects (font (size 1.27 1.27) (thickness 0.15)) (justify left bottom) hide)
    )
    (property "Author" "Antmicro" (at 315.595 178.435 0)
      (effects (font (size 1.27 1.27) (thickness 0.15)) (justify left bottom) hide)
    )
    (property "Voltage" "50V" (at 313.055 178.435 0)
      (effects (font (size 1.27 1.27)) (justify left bottom) hide)
    )
    (property "Dielectric" "X5R" (at 310.515 178.435 0)
      (effects (font (size 1.27 1.27)) (justify left bottom) hide)
    )
    (pin "1")
    (pin "2")
    (instances
      (project "data-center-rdimm-ddr4-tester"
        (path ""
          (reference "C205") (unit 1)
        )
      )
    )
  )

  (symbol (lib_id "antmicropower:GND") (at 334.645 163.195 0) (unit 1)
    (in_bom yes) (on_board yes) (dnp no) (fields_autoplaced)
    (property "Reference" "#PWR0292" (at 334.645 169.545 0)
      (effects (font (size 1.27 1.27)) hide)
    )
    (property "Value" "GND" (at 334.645 168.275 0)
      (effects (font (size 1.27 1.27)))
    )
    (property "Footprint" "" (at 334.645 163.195 0)
      (effects (font (size 1.27 1.27)) hide)
    )
    (property "Datasheet" "" (at 334.645 163.195 0)
      (effects (font (size 1.27 1.27)) hide)
    )
    (property "Author" "Antmicro" (at 343.535 170.815 0)
      (effects (font (size 1.27 1.27) (thickness 0.15)) (justify left bottom) hide)
    )
    (property "License" "Apache-2.0" (at 343.535 173.355 0)
      (effects (font (size 1.27 1.27) (thickness 0.15)) (justify left bottom) hide)
    )
    (pin "1")
    (instances
      (project "data-center-rdimm-ddr4-tester"
        (path ""
          (reference "#PWR0292") (unit 1)
        )
      )
    )
  )

  (symbol (lib_id "antmicropower:GND") (at 340.995 163.195 0) (unit 1)
    (in_bom yes) (on_board yes) (dnp no) (fields_autoplaced)
    (property "Reference" "#PWR0293" (at 340.995 169.545 0)
      (effects (font (size 1.27 1.27)) hide)
    )
    (property "Value" "GND" (at 340.995 168.275 0)
      (effects (font (size 1.27 1.27)))
    )
    (property "Footprint" "" (at 340.995 163.195 0)
      (effects (font (size 1.27 1.27)) hide)
    )
    (property "Datasheet" "" (at 340.995 163.195 0)
      (effects (font (size 1.27 1.27)) hide)
    )
    (property "Author" "Antmicro" (at 349.885 170.815 0)
      (effects (font (size 1.27 1.27) (thickness 0.15)) (justify left bottom) hide)
    )
    (property "License" "Apache-2.0" (at 349.885 173.355 0)
      (effects (font (size 1.27 1.27) (thickness 0.15)) (justify left bottom) hide)
    )
    (pin "1")
    (instances
      (project "data-center-rdimm-ddr4-tester"
        (path ""
          (reference "#PWR0293") (unit 1)
        )
      )
    )
  )

  (symbol (lib_id "antmicroCapacitors0402:C_100n_0402") (at 359.41 80.01 270) (unit 1)
    (in_bom yes) (on_board yes) (dnp no)
    (property "Reference" "C212" (at 359.41 80.645 90)
      (effects (font (size 1.524 1.524)) (justify left))
    )
    (property "Value" "C_100n_0402" (at 349.25 100.33 0)
      (effects (font (size 1.27 1.27) (thickness 0.15)) (justify left bottom) hide)
    )
    (property "Footprint" "antmicro-footprints:C_0402_1005Metric" (at 346.71 100.33 0)
      (effects (font (size 1.27 1.27) (thickness 0.15)) (justify left bottom) hide)
    )
    (property "Datasheet" "https://search.murata.co.jp/Ceramy/image/img/A01X/G101/ENG/GRM155R61H104KE14-01.pdf" (at 344.17 100.33 0)
      (effects (font (size 1.27 1.27) (thickness 0.15)) (justify left bottom) hide)
    )
    (property "Manufacturer" "Murata" (at 339.09 100.33 0)
      (effects (font (size 1.27 1.27) (thickness 0.15)) (justify left bottom) hide)
    )
    (property "MPN" "GRM155R61H104KE14D" (at 341.63 100.33 0)
      (effects (font (size 1.27 1.27) (thickness 0.15)) (justify left bottom) hide)
    )
    (property "Val" "100n" (at 359.41 84.455 90)
      (effects (font (size 1.27 1.27) (thickness 0.15)) (justify left))
    )
    (property "License" "Apache-2.0" (at 336.55 100.33 0)
      (effects (font (size 1.27 1.27) (thickness 0.15)) (justify left bottom) hide)
    )
    (property "Author" "Antmicro" (at 334.01 100.33 0)
      (effects (font (size 1.27 1.27) (thickness 0.15)) (justify left bottom) hide)
    )
    (property "Voltage" "50V" (at 331.47 100.33 0)
      (effects (font (size 1.27 1.27)) (justify left bottom) hide)
    )
    (property "Dielectric" "X5R" (at 328.93 100.33 0)
      (effects (font (size 1.27 1.27)) (justify left bottom) hide)
    )
    (pin "1")
    (pin "2")
    (instances
      (project "data-center-rdimm-ddr4-tester"
        (path ""
          (reference "C212") (unit 1)
        )
      )
    )
  )

  (symbol (lib_id "antmicroCapacitors0402:C_100n_0402") (at 365.76 80.01 270) (unit 1)
    (in_bom yes) (on_board yes) (dnp no)
    (property "Reference" "C213" (at 365.76 80.645 90)
      (effects (font (size 1.524 1.524)) (justify left))
    )
    (property "Value" "C_100n_0402" (at 355.6 100.33 0)
      (effects (font (size 1.27 1.27) (thickness 0.15)) (justify left bottom) hide)
    )
    (property "Footprint" "antmicro-footprints:C_0402_1005Metric" (at 353.06 100.33 0)
      (effects (font (size 1.27 1.27) (thickness 0.15)) (justify left bottom) hide)
    )
    (property "Datasheet" "https://search.murata.co.jp/Ceramy/image/img/A01X/G101/ENG/GRM155R61H104KE14-01.pdf" (at 350.52 100.33 0)
      (effects (font (size 1.27 1.27) (thickness 0.15)) (justify left bottom) hide)
    )
    (property "Manufacturer" "Murata" (at 345.44 100.33 0)
      (effects (font (size 1.27 1.27) (thickness 0.15)) (justify left bottom) hide)
    )
    (property "MPN" "GRM155R61H104KE14D" (at 347.98 100.33 0)
      (effects (font (size 1.27 1.27) (thickness 0.15)) (justify left bottom) hide)
    )
    (property "Val" "100n" (at 365.76 84.455 90)
      (effects (font (size 1.27 1.27) (thickness 0.15)) (justify left))
    )
    (property "License" "Apache-2.0" (at 342.9 100.33 0)
      (effects (font (size 1.27 1.27) (thickness 0.15)) (justify left bottom) hide)
    )
    (property "Author" "Antmicro" (at 340.36 100.33 0)
      (effects (font (size 1.27 1.27) (thickness 0.15)) (justify left bottom) hide)
    )
    (property "Voltage" "50V" (at 337.82 100.33 0)
      (effects (font (size 1.27 1.27)) (justify left bottom) hide)
    )
    (property "Dielectric" "X5R" (at 335.28 100.33 0)
      (effects (font (size 1.27 1.27)) (justify left bottom) hide)
    )
    (pin "1")
    (pin "2")
    (instances
      (project "data-center-rdimm-ddr4-tester"
        (path ""
          (reference "C213") (unit 1)
        )
      )
    )
  )

  (symbol (lib_id "antmicroCapacitors0402:C_100n_0402") (at 372.11 80.01 270) (unit 1)
    (in_bom yes) (on_board yes) (dnp no)
    (property "Reference" "C214" (at 372.11 80.645 90)
      (effects (font (size 1.524 1.524)) (justify left))
    )
    (property "Value" "C_100n_0402" (at 361.95 100.33 0)
      (effects (font (size 1.27 1.27) (thickness 0.15)) (justify left bottom) hide)
    )
    (property "Footprint" "antmicro-footprints:C_0402_1005Metric" (at 359.41 100.33 0)
      (effects (font (size 1.27 1.27) (thickness 0.15)) (justify left bottom) hide)
    )
    (property "Datasheet" "https://search.murata.co.jp/Ceramy/image/img/A01X/G101/ENG/GRM155R61H104KE14-01.pdf" (at 356.87 100.33 0)
      (effects (font (size 1.27 1.27) (thickness 0.15)) (justify left bottom) hide)
    )
    (property "Manufacturer" "Murata" (at 351.79 100.33 0)
      (effects (font (size 1.27 1.27) (thickness 0.15)) (justify left bottom) hide)
    )
    (property "MPN" "GRM155R61H104KE14D" (at 354.33 100.33 0)
      (effects (font (size 1.27 1.27) (thickness 0.15)) (justify left bottom) hide)
    )
    (property "Val" "100n" (at 372.11 84.455 90)
      (effects (font (size 1.27 1.27) (thickness 0.15)) (justify left))
    )
    (property "License" "Apache-2.0" (at 349.25 100.33 0)
      (effects (font (size 1.27 1.27) (thickness 0.15)) (justify left bottom) hide)
    )
    (property "Author" "Antmicro" (at 346.71 100.33 0)
      (effects (font (size 1.27 1.27) (thickness 0.15)) (justify left bottom) hide)
    )
    (property "Voltage" "50V" (at 344.17 100.33 0)
      (effects (font (size 1.27 1.27)) (justify left bottom) hide)
    )
    (property "Dielectric" "X5R" (at 341.63 100.33 0)
      (effects (font (size 1.27 1.27)) (justify left bottom) hide)
    )
    (pin "1")
    (pin "2")
    (instances
      (project "data-center-rdimm-ddr4-tester"
        (path ""
          (reference "C214") (unit 1)
        )
      )
    )
  )

  (symbol (lib_id "antmicroCapacitors0402:C_100n_0402") (at 334.01 80.01 270) (unit 1)
    (in_bom yes) (on_board yes) (dnp no)
    (property "Reference" "C208" (at 334.01 80.645 90)
      (effects (font (size 1.524 1.524)) (justify left))
    )
    (property "Value" "C_100n_0402" (at 323.85 100.33 0)
      (effects (font (size 1.27 1.27) (thickness 0.15)) (justify left bottom) hide)
    )
    (property "Footprint" "antmicro-footprints:C_0402_1005Metric" (at 321.31 100.33 0)
      (effects (font (size 1.27 1.27) (thickness 0.15)) (justify left bottom) hide)
    )
    (property "Datasheet" "https://search.murata.co.jp/Ceramy/image/img/A01X/G101/ENG/GRM155R61H104KE14-01.pdf" (at 318.77 100.33 0)
      (effects (font (size 1.27 1.27) (thickness 0.15)) (justify left bottom) hide)
    )
    (property "Manufacturer" "Murata" (at 313.69 100.33 0)
      (effects (font (size 1.27 1.27) (thickness 0.15)) (justify left bottom) hide)
    )
    (property "MPN" "GRM155R61H104KE14D" (at 316.23 100.33 0)
      (effects (font (size 1.27 1.27) (thickness 0.15)) (justify left bottom) hide)
    )
    (property "Val" "100n" (at 334.01 84.455 90)
      (effects (font (size 1.27 1.27) (thickness 0.15)) (justify left))
    )
    (property "License" "Apache-2.0" (at 311.15 100.33 0)
      (effects (font (size 1.27 1.27) (thickness 0.15)) (justify left bottom) hide)
    )
    (property "Author" "Antmicro" (at 308.61 100.33 0)
      (effects (font (size 1.27 1.27) (thickness 0.15)) (justify left bottom) hide)
    )
    (property "Voltage" "50V" (at 306.07 100.33 0)
      (effects (font (size 1.27 1.27)) (justify left bottom) hide)
    )
    (property "Dielectric" "X5R" (at 303.53 100.33 0)
      (effects (font (size 1.27 1.27)) (justify left bottom) hide)
    )
    (pin "1")
    (pin "2")
    (instances
      (project "data-center-rdimm-ddr4-tester"
        (path ""
          (reference "C208") (unit 1)
        )
      )
    )
  )

  (symbol (lib_id "antmicroCapacitors0402:C_100n_0402") (at 340.36 80.01 270) (unit 1)
    (in_bom yes) (on_board yes) (dnp no)
    (property "Reference" "C209" (at 340.36 80.645 90)
      (effects (font (size 1.524 1.524)) (justify left))
    )
    (property "Value" "C_100n_0402" (at 330.2 100.33 0)
      (effects (font (size 1.27 1.27) (thickness 0.15)) (justify left bottom) hide)
    )
    (property "Footprint" "antmicro-footprints:C_0402_1005Metric" (at 327.66 100.33 0)
      (effects (font (size 1.27 1.27) (thickness 0.15)) (justify left bottom) hide)
    )
    (property "Datasheet" "https://search.murata.co.jp/Ceramy/image/img/A01X/G101/ENG/GRM155R61H104KE14-01.pdf" (at 325.12 100.33 0)
      (effects (font (size 1.27 1.27) (thickness 0.15)) (justify left bottom) hide)
    )
    (property "Manufacturer" "Murata" (at 320.04 100.33 0)
      (effects (font (size 1.27 1.27) (thickness 0.15)) (justify left bottom) hide)
    )
    (property "MPN" "GRM155R61H104KE14D" (at 322.58 100.33 0)
      (effects (font (size 1.27 1.27) (thickness 0.15)) (justify left bottom) hide)
    )
    (property "Val" "100n" (at 340.36 84.455 90)
      (effects (font (size 1.27 1.27) (thickness 0.15)) (justify left))
    )
    (property "License" "Apache-2.0" (at 317.5 100.33 0)
      (effects (font (size 1.27 1.27) (thickness 0.15)) (justify left bottom) hide)
    )
    (property "Author" "Antmicro" (at 314.96 100.33 0)
      (effects (font (size 1.27 1.27) (thickness 0.15)) (justify left bottom) hide)
    )
    (property "Voltage" "50V" (at 312.42 100.33 0)
      (effects (font (size 1.27 1.27)) (justify left bottom) hide)
    )
    (property "Dielectric" "X5R" (at 309.88 100.33 0)
      (effects (font (size 1.27 1.27)) (justify left bottom) hide)
    )
    (pin "1")
    (pin "2")
    (instances
      (project "data-center-rdimm-ddr4-tester"
        (path ""
          (reference "C209") (unit 1)
        )
      )
    )
  )

  (symbol (lib_id "antmicroCapacitors0402:C_100n_0402") (at 346.71 80.01 270) (unit 1)
    (in_bom yes) (on_board yes) (dnp no)
    (property "Reference" "C210" (at 346.71 80.645 90)
      (effects (font (size 1.524 1.524)) (justify left))
    )
    (property "Value" "C_100n_0402" (at 336.55 100.33 0)
      (effects (font (size 1.27 1.27) (thickness 0.15)) (justify left bottom) hide)
    )
    (property "Footprint" "antmicro-footprints:C_0402_1005Metric" (at 334.01 100.33 0)
      (effects (font (size 1.27 1.27) (thickness 0.15)) (justify left bottom) hide)
    )
    (property "Datasheet" "https://search.murata.co.jp/Ceramy/image/img/A01X/G101/ENG/GRM155R61H104KE14-01.pdf" (at 331.47 100.33 0)
      (effects (font (size 1.27 1.27) (thickness 0.15)) (justify left bottom) hide)
    )
    (property "Manufacturer" "Murata" (at 326.39 100.33 0)
      (effects (font (size 1.27 1.27) (thickness 0.15)) (justify left bottom) hide)
    )
    (property "MPN" "GRM155R61H104KE14D" (at 328.93 100.33 0)
      (effects (font (size 1.27 1.27) (thickness 0.15)) (justify left bottom) hide)
    )
    (property "Val" "100n" (at 346.71 84.455 90)
      (effects (font (size 1.27 1.27) (thickness 0.15)) (justify left))
    )
    (property "License" "Apache-2.0" (at 323.85 100.33 0)
      (effects (font (size 1.27 1.27) (thickness 0.15)) (justify left bottom) hide)
    )
    (property "Author" "Antmicro" (at 321.31 100.33 0)
      (effects (font (size 1.27 1.27) (thickness 0.15)) (justify left bottom) hide)
    )
    (property "Voltage" "50V" (at 318.77 100.33 0)
      (effects (font (size 1.27 1.27)) (justify left bottom) hide)
    )
    (property "Dielectric" "X5R" (at 316.23 100.33 0)
      (effects (font (size 1.27 1.27)) (justify left bottom) hide)
    )
    (pin "1")
    (pin "2")
    (instances
      (project "data-center-rdimm-ddr4-tester"
        (path ""
          (reference "C210") (unit 1)
        )
      )
    )
  )

  (symbol (lib_id "antmicroCapacitors0402:C_100n_0402") (at 353.06 80.01 270) (unit 1)
    (in_bom yes) (on_board yes) (dnp no)
    (property "Reference" "C211" (at 353.06 80.645 90)
      (effects (font (size 1.524 1.524)) (justify left))
    )
    (property "Value" "C_100n_0402" (at 342.9 100.33 0)
      (effects (font (size 1.27 1.27) (thickness 0.15)) (justify left bottom) hide)
    )
    (property "Footprint" "antmicro-footprints:C_0402_1005Metric" (at 340.36 100.33 0)
      (effects (font (size 1.27 1.27) (thickness 0.15)) (justify left bottom) hide)
    )
    (property "Datasheet" "https://search.murata.co.jp/Ceramy/image/img/A01X/G101/ENG/GRM155R61H104KE14-01.pdf" (at 337.82 100.33 0)
      (effects (font (size 1.27 1.27) (thickness 0.15)) (justify left bottom) hide)
    )
    (property "Manufacturer" "Murata" (at 332.74 100.33 0)
      (effects (font (size 1.27 1.27) (thickness 0.15)) (justify left bottom) hide)
    )
    (property "MPN" "GRM155R61H104KE14D" (at 335.28 100.33 0)
      (effects (font (size 1.27 1.27) (thickness 0.15)) (justify left bottom) hide)
    )
    (property "Val" "100n" (at 353.06 84.455 90)
      (effects (font (size 1.27 1.27) (thickness 0.15)) (justify left))
    )
    (property "License" "Apache-2.0" (at 330.2 100.33 0)
      (effects (font (size 1.27 1.27) (thickness 0.15)) (justify left bottom) hide)
    )
    (property "Author" "Antmicro" (at 327.66 100.33 0)
      (effects (font (size 1.27 1.27) (thickness 0.15)) (justify left bottom) hide)
    )
    (property "Voltage" "50V" (at 325.12 100.33 0)
      (effects (font (size 1.27 1.27)) (justify left bottom) hide)
    )
    (property "Dielectric" "X5R" (at 322.58 100.33 0)
      (effects (font (size 1.27 1.27)) (justify left bottom) hide)
    )
    (pin "1")
    (pin "2")
    (instances
      (project "data-center-rdimm-ddr4-tester"
        (path ""
          (reference "C211") (unit 1)
        )
      )
    )
  )

  (symbol (lib_id "antmicropower:GND") (at 334.01 85.09 0) (unit 1)
    (in_bom yes) (on_board yes) (dnp no) (fields_autoplaced)
    (property "Reference" "#PWR034" (at 334.01 91.44 0)
      (effects (font (size 1.27 1.27)) hide)
    )
    (property "Value" "GND" (at 334.01 90.17 0)
      (effects (font (size 1.27 1.27)))
    )
    (property "Footprint" "" (at 334.01 85.09 0)
      (effects (font (size 1.27 1.27)) hide)
    )
    (property "Datasheet" "" (at 334.01 85.09 0)
      (effects (font (size 1.27 1.27)) hide)
    )
    (property "Author" "Antmicro" (at 342.9 92.71 0)
      (effects (font (size 1.27 1.27) (thickness 0.15)) (justify left bottom) hide)
    )
    (property "License" "Apache-2.0" (at 342.9 95.25 0)
      (effects (font (size 1.27 1.27) (thickness 0.15)) (justify left bottom) hide)
    )
    (pin "1")
    (instances
      (project "data-center-rdimm-ddr4-tester"
        (path ""
          (reference "#PWR034") (unit 1)
        )
      )
    )
  )

  (symbol (lib_id "antmicropower:GND") (at 340.36 85.09 0) (unit 1)
    (in_bom yes) (on_board yes) (dnp no) (fields_autoplaced)
    (property "Reference" "#PWR050" (at 340.36 91.44 0)
      (effects (font (size 1.27 1.27)) hide)
    )
    (property "Value" "GND" (at 340.36 90.17 0)
      (effects (font (size 1.27 1.27)))
    )
    (property "Footprint" "" (at 340.36 85.09 0)
      (effects (font (size 1.27 1.27)) hide)
    )
    (property "Datasheet" "" (at 340.36 85.09 0)
      (effects (font (size 1.27 1.27)) hide)
    )
    (property "Author" "Antmicro" (at 349.25 92.71 0)
      (effects (font (size 1.27 1.27) (thickness 0.15)) (justify left bottom) hide)
    )
    (property "License" "Apache-2.0" (at 349.25 95.25 0)
      (effects (font (size 1.27 1.27) (thickness 0.15)) (justify left bottom) hide)
    )
    (pin "1")
    (instances
      (project "data-center-rdimm-ddr4-tester"
        (path ""
          (reference "#PWR050") (unit 1)
        )
      )
    )
  )

  (symbol (lib_id "antmicropower:GND") (at 346.71 85.09 0) (unit 1)
    (in_bom yes) (on_board yes) (dnp no) (fields_autoplaced)
    (property "Reference" "#PWR051" (at 346.71 91.44 0)
      (effects (font (size 1.27 1.27)) hide)
    )
    (property "Value" "GND" (at 346.71 90.17 0)
      (effects (font (size 1.27 1.27)))
    )
    (property "Footprint" "" (at 346.71 85.09 0)
      (effects (font (size 1.27 1.27)) hide)
    )
    (property "Datasheet" "" (at 346.71 85.09 0)
      (effects (font (size 1.27 1.27)) hide)
    )
    (property "Author" "Antmicro" (at 355.6 92.71 0)
      (effects (font (size 1.27 1.27) (thickness 0.15)) (justify left bottom) hide)
    )
    (property "License" "Apache-2.0" (at 355.6 95.25 0)
      (effects (font (size 1.27 1.27) (thickness 0.15)) (justify left bottom) hide)
    )
    (pin "1")
    (instances
      (project "data-center-rdimm-ddr4-tester"
        (path ""
          (reference "#PWR051") (unit 1)
        )
      )
    )
  )

  (symbol (lib_id "antmicropower:GND") (at 353.06 85.09 0) (unit 1)
    (in_bom yes) (on_board yes) (dnp no) (fields_autoplaced)
    (property "Reference" "#PWR052" (at 353.06 91.44 0)
      (effects (font (size 1.27 1.27)) hide)
    )
    (property "Value" "GND" (at 353.06 90.17 0)
      (effects (font (size 1.27 1.27)))
    )
    (property "Footprint" "" (at 353.06 85.09 0)
      (effects (font (size 1.27 1.27)) hide)
    )
    (property "Datasheet" "" (at 353.06 85.09 0)
      (effects (font (size 1.27 1.27)) hide)
    )
    (property "Author" "Antmicro" (at 361.95 92.71 0)
      (effects (font (size 1.27 1.27) (thickness 0.15)) (justify left bottom) hide)
    )
    (property "License" "Apache-2.0" (at 361.95 95.25 0)
      (effects (font (size 1.27 1.27) (thickness 0.15)) (justify left bottom) hide)
    )
    (pin "1")
    (instances
      (project "data-center-rdimm-ddr4-tester"
        (path ""
          (reference "#PWR052") (unit 1)
        )
      )
    )
  )

  (symbol (lib_id "antmicropower:GND") (at 359.41 85.09 0) (unit 1)
    (in_bom yes) (on_board yes) (dnp no) (fields_autoplaced)
    (property "Reference" "#PWR053" (at 359.41 91.44 0)
      (effects (font (size 1.27 1.27)) hide)
    )
    (property "Value" "GND" (at 359.41 90.17 0)
      (effects (font (size 1.27 1.27)))
    )
    (property "Footprint" "" (at 359.41 85.09 0)
      (effects (font (size 1.27 1.27)) hide)
    )
    (property "Datasheet" "" (at 359.41 85.09 0)
      (effects (font (size 1.27 1.27)) hide)
    )
    (property "Author" "Antmicro" (at 368.3 92.71 0)
      (effects (font (size 1.27 1.27) (thickness 0.15)) (justify left bottom) hide)
    )
    (property "License" "Apache-2.0" (at 368.3 95.25 0)
      (effects (font (size 1.27 1.27) (thickness 0.15)) (justify left bottom) hide)
    )
    (pin "1")
    (instances
      (project "data-center-rdimm-ddr4-tester"
        (path ""
          (reference "#PWR053") (unit 1)
        )
      )
    )
  )

  (symbol (lib_id "antmicropower:GND") (at 365.76 85.09 0) (unit 1)
    (in_bom yes) (on_board yes) (dnp no) (fields_autoplaced)
    (property "Reference" "#PWR054" (at 365.76 91.44 0)
      (effects (font (size 1.27 1.27)) hide)
    )
    (property "Value" "GND" (at 365.76 90.17 0)
      (effects (font (size 1.27 1.27)))
    )
    (property "Footprint" "" (at 365.76 85.09 0)
      (effects (font (size 1.27 1.27)) hide)
    )
    (property "Datasheet" "" (at 365.76 85.09 0)
      (effects (font (size 1.27 1.27)) hide)
    )
    (property "Author" "Antmicro" (at 374.65 92.71 0)
      (effects (font (size 1.27 1.27) (thickness 0.15)) (justify left bottom) hide)
    )
    (property "License" "Apache-2.0" (at 374.65 95.25 0)
      (effects (font (size 1.27 1.27) (thickness 0.15)) (justify left bottom) hide)
    )
    (pin "1")
    (instances
      (project "data-center-rdimm-ddr4-tester"
        (path ""
          (reference "#PWR054") (unit 1)
        )
      )
    )
  )

  (symbol (lib_id "antmicropower:GND") (at 372.11 85.09 0) (unit 1)
    (in_bom yes) (on_board yes) (dnp no) (fields_autoplaced)
    (property "Reference" "#PWR055" (at 372.11 91.44 0)
      (effects (font (size 1.27 1.27)) hide)
    )
    (property "Value" "GND" (at 372.11 90.17 0)
      (effects (font (size 1.27 1.27)))
    )
    (property "Footprint" "" (at 372.11 85.09 0)
      (effects (font (size 1.27 1.27)) hide)
    )
    (property "Datasheet" "" (at 372.11 85.09 0)
      (effects (font (size 1.27 1.27)) hide)
    )
    (property "Author" "Antmicro" (at 381 92.71 0)
      (effects (font (size 1.27 1.27) (thickness 0.15)) (justify left bottom) hide)
    )
    (property "License" "Apache-2.0" (at 381 95.25 0)
      (effects (font (size 1.27 1.27) (thickness 0.15)) (justify left bottom) hide)
    )
    (pin "1")
    (instances
      (project "data-center-rdimm-ddr4-tester"
        (path ""
          (reference "#PWR055") (unit 1)
        )
      )
    )
  )

  (symbol (lib_id "antmicroResistors0402:R_0R_0402") (at 210.82 130.175 90) (unit 1)
    (in_bom no) (on_board yes) (dnp yes)
    (property "Reference" "R185" (at 213.36 126.365 90)
      (effects (font (size 1.524 1.524)) (justify right))
    )
    (property "Value" "R_0R_0402" (at 223.52 109.855 0)
      (effects (font (size 1.27 1.27) (thickness 0.15)) (justify left bottom) hide)
    )
    (property "Footprint" "antmicro-footprints:R_0402_1005Metric" (at 226.06 109.855 0)
      (effects (font (size 1.27 1.27) (thickness 0.15)) (justify left bottom) hide)
    )
    (property "Datasheet" "https://industrial.panasonic.com/cdbs/www-data/pdf/RDA0000/AOA0000C301.pdf" (at 228.6 109.855 0)
      (effects (font (size 1.27 1.27) (thickness 0.15)) (justify left bottom) hide)
    )
    (property "Manufacturer" "Panasonic" (at 233.68 109.855 0)
      (effects (font (size 1.27 1.27) (thickness 0.15)) (justify left bottom) hide)
    )
    (property "MPN" "ERJ2GE0R00X" (at 231.14 109.855 0)
      (effects (font (size 1.27 1.27) (thickness 0.15)) (justify left bottom) hide)
    )
    (property "Val" "0R" (at 213.36 129.5399 90)
      (effects (font (size 1.27 1.27) (thickness 0.15)) (justify right))
    )
    (property "License" "Apache-2.0" (at 236.22 109.855 0)
      (effects (font (size 1.27 1.27) (thickness 0.15)) (justify left bottom) hide)
    )
    (property "Author" "Antmicro" (at 238.76 109.855 0)
      (effects (font (size 1.27 1.27) (thickness 0.15)) (justify left bottom) hide)
    )
    (property "Tolerance" "~" (at 220.98 109.855 0)
      (effects (font (size 1.27 1.27)) (justify left bottom) hide)
    )
    (property "Current" "1A" (at 241.3 109.855 0)
      (effects (font (size 1.27 1.27) (thickness 0.15)) (justify left bottom) hide)
    )
    (property "DNP" "DNP" (at 210.82 127.635 0)
      (effects (font (size 1.27 1.27)))
    )
    (pin "1")
    (pin "2")
    (instances
      (project "data-center-rdimm-ddr4-tester"
        (path ""
          (reference "R185") (unit 1)
        )
      )
    )
  )

  (symbol (lib_id "antmicropower:GND") (at 210.82 130.175 0) (unit 1)
    (in_bom yes) (on_board yes) (dnp no) (fields_autoplaced)
    (property "Reference" "#PWR0317" (at 210.82 136.525 0)
      (effects (font (size 1.27 1.27)) hide)
    )
    (property "Value" "GND" (at 210.82 135.255 0)
      (effects (font (size 1.27 1.27)))
    )
    (property "Footprint" "" (at 210.82 130.175 0)
      (effects (font (size 1.27 1.27)) hide)
    )
    (property "Datasheet" "" (at 210.82 130.175 0)
      (effects (font (size 1.27 1.27)) hide)
    )
    (property "Author" "Antmicro" (at 219.71 137.795 0)
      (effects (font (size 1.27 1.27) (thickness 0.15)) (justify left bottom) hide)
    )
    (property "License" "Apache-2.0" (at 219.71 140.335 0)
      (effects (font (size 1.27 1.27) (thickness 0.15)) (justify left bottom) hide)
    )
    (pin "1")
    (instances
      (project "data-center-rdimm-ddr4-tester"
        (path ""
          (reference "#PWR0317") (unit 1)
        )
      )
    )
  )

  (symbol (lib_id "antmicroResistors0402:R_0R_0402") (at 341.63 238.125 0) (unit 1)
    (in_bom yes) (on_board yes) (dnp no)
    (property "Reference" "R158" (at 344.17 234.315 0)
      (effects (font (size 1.524 1.524)))
    )
    (property "Value" "R_0R_0402" (at 361.95 250.825 0)
      (effects (font (size 1.27 1.27) (thickness 0.15)) (justify left bottom) hide)
    )
    (property "Footprint" "antmicro-footprints:R_0402_1005Metric" (at 361.95 253.365 0)
      (effects (font (size 1.27 1.27) (thickness 0.15)) (justify left bottom) hide)
    )
    (property "Datasheet" "https://industrial.panasonic.com/cdbs/www-data/pdf/RDA0000/AOA0000C301.pdf" (at 361.95 255.905 0)
      (effects (font (size 1.27 1.27) (thickness 0.15)) (justify left bottom) hide)
    )
    (property "Manufacturer" "Panasonic" (at 361.95 260.985 0)
      (effects (font (size 1.27 1.27) (thickness 0.15)) (justify left bottom) hide)
    )
    (property "MPN" "ERJ2GE0R00X" (at 361.95 258.445 0)
      (effects (font (size 1.27 1.27) (thickness 0.15)) (justify left bottom) hide)
    )
    (property "Val" "0R" (at 344.17 236.22 0)
      (effects (font (size 1.27 1.27) (thickness 0.15)))
    )
    (property "License" "Apache-2.0" (at 361.95 263.525 0)
      (effects (font (size 1.27 1.27) (thickness 0.15)) (justify left bottom) hide)
    )
    (property "Author" "Antmicro" (at 361.95 266.065 0)
      (effects (font (size 1.27 1.27) (thickness 0.15)) (justify left bottom) hide)
    )
    (property "Tolerance" "~" (at 361.95 248.285 0)
      (effects (font (size 1.27 1.27)) (justify left bottom) hide)
    )
    (property "Current" "1A" (at 361.95 268.605 0)
      (effects (font (size 1.27 1.27) (thickness 0.15)) (justify left bottom) hide)
    )
    (pin "1")
    (pin "2")
    (instances
      (project "data-center-rdimm-ddr4-tester"
        (path ""
          (reference "R158") (unit 1)
        )
      )
    )
  )

  (symbol (lib_id "antmicroResistors0402:R_100k_0402") (at 208.28 121.92 90) (unit 1)
    (in_bom yes) (on_board yes) (dnp no) (fields_autoplaced)
    (property "Reference" "R186" (at 210.82 118.11 90)
      (effects (font (size 1.524 1.524)) (justify right))
    )
    (property "Value" "R_100k_0402" (at 220.98 101.6 0)
      (effects (font (size 1.27 1.27) (thickness 0.15)) (justify left bottom) hide)
    )
    (property "Footprint" "antmicro-footprints:R_0402_1005Metric" (at 223.52 101.6 0)
      (effects (font (size 1.27 1.27) (thickness 0.15)) (justify left bottom) hide)
    )
    (property "Datasheet" "https://www.bourns.com/docs/product-datasheets/cr.pdf" (at 226.06 101.6 0)
      (effects (font (size 1.27 1.27) (thickness 0.15)) (justify left bottom) hide)
    )
    (property "Manufacturer" "Bourns" (at 231.14 101.6 0)
      (effects (font (size 1.27 1.27) (thickness 0.15)) (justify left bottom) hide)
    )
    (property "MPN" "CR0402-FX-1003GLF" (at 228.6 101.6 0)
      (effects (font (size 1.27 1.27) (thickness 0.15)) (justify left bottom) hide)
    )
    (property "Val" "100k" (at 210.82 121.2849 90)
      (effects (font (size 1.27 1.27) (thickness 0.15)) (justify right))
    )
    (property "License" "Apache-2.0" (at 233.68 101.6 0)
      (effects (font (size 1.27 1.27) (thickness 0.15)) (justify left bottom) hide)
    )
    (property "Author" "Antmicro" (at 236.22 101.6 0)
      (effects (font (size 1.27 1.27) (thickness 0.15)) (justify left bottom) hide)
    )
    (property "Tolerance" "1%" (at 218.44 101.6 0)
      (effects (font (size 1.27 1.27)) (justify left bottom) hide)
    )
    (pin "1")
    (pin "2")
    (instances
      (project "data-center-rdimm-ddr4-tester"
        (path ""
          (reference "R186") (unit 1)
        )
      )
    )
  )

  (symbol (lib_id "antmicroResistors0402:R_0R_0402") (at 43.18 48.895 0) (unit 1)
    (in_bom no) (on_board yes) (dnp yes)
    (property "Reference" "R157" (at 45.72 45.085 0)
      (effects (font (size 1.524 1.524)))
    )
    (property "Value" "R_0R_0402" (at 63.5 61.595 0)
      (effects (font (size 1.27 1.27) (thickness 0.15)) (justify left bottom) hide)
    )
    (property "Footprint" "antmicro-footprints:R_0402_1005Metric" (at 63.5 64.135 0)
      (effects (font (size 1.27 1.27) (thickness 0.15)) (justify left bottom) hide)
    )
    (property "Datasheet" "https://industrial.panasonic.com/cdbs/www-data/pdf/RDA0000/AOA0000C301.pdf" (at 63.5 66.675 0)
      (effects (font (size 1.27 1.27) (thickness 0.15)) (justify left bottom) hide)
    )
    (property "Manufacturer" "Panasonic" (at 63.5 71.755 0)
      (effects (font (size 1.27 1.27) (thickness 0.15)) (justify left bottom) hide)
    )
    (property "MPN" "ERJ2GE0R00X" (at 63.5 69.215 0)
      (effects (font (size 1.27 1.27) (thickness 0.15)) (justify left bottom) hide)
    )
    (property "Val" "0R" (at 45.72 46.99 0)
      (effects (font (size 1.27 1.27) (thickness 0.15)))
    )
    (property "License" "Apache-2.0" (at 63.5 74.295 0)
      (effects (font (size 1.27 1.27) (thickness 0.15)) (justify left bottom) hide)
    )
    (property "Author" "Antmicro" (at 63.5 76.835 0)
      (effects (font (size 1.27 1.27) (thickness 0.15)) (justify left bottom) hide)
    )
    (property "Tolerance" "~" (at 63.5 59.055 0)
      (effects (font (size 1.27 1.27)) (justify left bottom) hide)
    )
    (property "Current" "1A" (at 63.5 79.375 0)
      (effects (font (size 1.27 1.27) (thickness 0.15)) (justify left bottom) hide)
    )
    (property "DNP" "DNP" (at 45.72 48.895 0)
      (effects (font (size 1.27 1.27)))
    )
    (pin "1")
    (pin "2")
    (instances
      (project "data-center-rdimm-ddr4-tester"
        (path ""
          (reference "R157") (unit 1)
        )
      )
    )
  )

  (symbol (lib_id "antmicropower:GND") (at 222.25 135.89 0) (unit 1)
    (in_bom yes) (on_board yes) (dnp no) (fields_autoplaced)
    (property "Reference" "#PWR0121" (at 222.25 142.24 0)
      (effects (font (size 1.27 1.27)) hide)
    )
    (property "Value" "GND" (at 222.25 140.97 0)
      (effects (font (size 1.27 1.27)))
    )
    (property "Footprint" "" (at 222.25 135.89 0)
      (effects (font (size 1.27 1.27)) hide)
    )
    (property "Datasheet" "" (at 222.25 135.89 0)
      (effects (font (size 1.27 1.27)) hide)
    )
    (property "Author" "Antmicro" (at 231.14 143.51 0)
      (effects (font (size 1.27 1.27) (thickness 0.15)) (justify left bottom) hide)
    )
    (property "License" "Apache-2.0" (at 231.14 146.05 0)
      (effects (font (size 1.27 1.27) (thickness 0.15)) (justify left bottom) hide)
    )
    (pin "1")
    (instances
      (project "data-center-rdimm-ddr4-tester"
        (path ""
          (reference "#PWR0121") (unit 1)
        )
      )
    )
  )
)
